FILE_TYPE = MACRO_DRAWING;
SET COLOR_WIRE YELLOW;
SET COLOR_PROP ORANGE;
SET COLOR_DOT WHITE;
SET COLOR_ARC YELLOW;
SET COLOR_BODY GREEN;
SET COLOR_NOTE PURPLE;
SET PROP_DISPLAY VALUE;
SET PAGE_NUMBER P317;
FORCEADD OFFPAGE..1
(-3375 -925);
FORCEPROP 2 LAST $XR0 173 
J 0
(-3627 -925);
DISPLAY 0.638298 (-3627 -925);
PAINT MONO (-3627 -925);
FORCEPROP 2 LAST PATH I1
J 0
(-3625 -875);
DISPLAY 1.021277 (-3625 -875);
DISPLAY INVISIBLE (-3625 -875);
FORCEPROP 2 LAST CDS_LIB standard
J 0
(-3375 -925);
DISPLAY INVISIBLE (-3375 -925);
FORCEPROP 1 LAST COMMENT_BODY TRUE
J 0
(-3250 -1025);
DISPLAY 0.872340 (-3250 -1025);
PAINT GREEN (-3250 -1025);
DISPLAY INVISIBLE (-3250 -1025);
FORCEPROP 1 LAST OFFPAGE TRUE
J 0
(-3050 -1050);
DISPLAY 0.872340 (-3050 -1050);
PAINT AQUA (-3050 -1050);
DISPLAY INVISIBLE (-3050 -1050);
FORCEADD OFFPAGE..5
(-3375 -625);
FORCEPROP 2 LAST $XR0 29 
J 0
(-3629 -625);
DISPLAY 0.638298 (-3629 -625);
PAINT MONO (-3629 -625);
FORCEPROP 2 LAST PATH I10
J 0
(-3625 -575);
DISPLAY 1.021277 (-3625 -575);
DISPLAY INVISIBLE (-3625 -575);
FORCEPROP 2 LAST CDS_LIB standard
J 0
(-3375 -625);
DISPLAY INVISIBLE (-3375 -625);
FORCEPROP 1 LAST OFFPAGE TRUE
J 0
(-3050 -750);
DISPLAY 0.872340 (-3050 -750);
PAINT AQUA (-3050 -750);
DISPLAY INVISIBLE (-3050 -750);
FORCEPROP 1 LAST COMMENT_BODY TRUE
J 0
(-3275 -700);
DISPLAY 1.170213 (-3275 -700);
PAINT GREEN (-3275 -700);
DISPLAY INVISIBLE (-3275 -700);
FORCEADD OFFPAGE..1
(-3375 -175);
FORCEPROP 2 LAST $XR0 175 
J 0
(-3627 -175);
DISPLAY 0.638298 (-3627 -175);
PAINT MONO (-3627 -175);
FORCEPROP 2 LAST PATH I12
J 0
(-3625 -125);
DISPLAY 1.021277 (-3625 -125);
DISPLAY INVISIBLE (-3625 -125);
FORCEPROP 2 LAST CDS_LIB standard
J 0
(-3375 -175);
DISPLAY INVISIBLE (-3375 -175);
FORCEPROP 1 LAST COMMENT_BODY TRUE
J 0
(-3250 -275);
DISPLAY 0.872340 (-3250 -275);
PAINT GREEN (-3250 -275);
DISPLAY INVISIBLE (-3250 -275);
FORCEPROP 1 LAST OFFPAGE TRUE
J 0
(-3050 -300);
DISPLAY 0.872340 (-3050 -300);
PAINT AQUA (-3050 -300);
DISPLAY INVISIBLE (-3050 -300);
FORCEADD OFFPAGE..1
(-3375 -25);
FORCEPROP 2 LAST $XR0 173 
J 0
(-3627 -25);
DISPLAY 0.638298 (-3627 -25);
PAINT MONO (-3627 -25);
FORCEPROP 2 LAST PATH I13
J 0
(-3625 25);
DISPLAY 1.021277 (-3625 25);
DISPLAY INVISIBLE (-3625 25);
FORCEPROP 2 LAST CDS_LIB standard
J 0
(-3375 -25);
DISPLAY INVISIBLE (-3375 -25);
FORCEPROP 1 LAST OFFPAGE TRUE
J 0
(-3050 -150);
DISPLAY 0.872340 (-3050 -150);
PAINT AQUA (-3050 -150);
DISPLAY INVISIBLE (-3050 -150);
FORCEPROP 1 LAST COMMENT_BODY TRUE
J 0
(-3250 -125);
DISPLAY 0.872340 (-3250 -125);
PAINT GREEN (-3250 -125);
DISPLAY INVISIBLE (-3250 -125);
FORCEADD OFFPAGE..1
(-3375 -75);
FORCEPROP 2 LAST $XR0 173 
J 0
(-3627 -75);
DISPLAY 0.638298 (-3627 -75);
PAINT MONO (-3627 -75);
FORCEPROP 2 LAST PATH I14
J 0
(-3625 -25);
DISPLAY 1.021277 (-3625 -25);
DISPLAY INVISIBLE (-3625 -25);
FORCEPROP 2 LAST CDS_LIB standard
J 0
(-3375 -75);
DISPLAY INVISIBLE (-3375 -75);
FORCEPROP 1 LAST OFFPAGE TRUE
J 0
(-3050 -200);
DISPLAY 0.872340 (-3050 -200);
PAINT AQUA (-3050 -200);
DISPLAY INVISIBLE (-3050 -200);
FORCEPROP 1 LAST COMMENT_BODY TRUE
J 0
(-3250 -175);
DISPLAY 0.872340 (-3250 -175);
PAINT GREEN (-3250 -175);
DISPLAY INVISIBLE (-3250 -175);
FORCEADD OFFPAGE..2
R 2
(-3375 275);
FORCEPROP 2 LAST $XR0 29 
J 0
(-3629 275);
DISPLAY 0.638298 (-3629 275);
PAINT MONO (-3629 275);
FORCEPROP 2 LAST PATH I15
J 0
(-3625 325);
DISPLAY 1.021277 (-3625 325);
DISPLAY INVISIBLE (-3625 325);
FORCEPROP 2 LAST CDS_LIB standard
J 0
(-3375 275);
DISPLAY INVISIBLE (-3375 275);
FORCEPROP 1 LAST COMMENT_BODY TRUE
J 2
(-3330 180);
DISPLAY 0.872340 (-3330 180);
PAINT GREEN (-3330 180);
DISPLAY INVISIBLE (-3330 180);
FORCEPROP 1 LAST OFFPAGE TRUE
J 2
(-3700 150);
DISPLAY 0.872340 (-3700 150);
PAINT AQUA (-3700 150);
DISPLAY INVISIBLE (-3700 150);
FORCEADD OFFPAGE..5
(-3375 225);
FORCEPROP 2 LAST $XR0 29 
J 0
(-3629 225);
DISPLAY 0.638298 (-3629 225);
PAINT MONO (-3629 225);
FORCEPROP 2 LAST PATH I16
J 0
(-3625 275);
DISPLAY 1.021277 (-3625 275);
DISPLAY INVISIBLE (-3625 275);
FORCEPROP 2 LAST CDS_LIB standard
J 0
(-3375 225);
DISPLAY INVISIBLE (-3375 225);
FORCEPROP 1 LAST COMMENT_BODY TRUE
J 0
(-3275 150);
DISPLAY 1.170213 (-3275 150);
PAINT GREEN (-3275 150);
DISPLAY INVISIBLE (-3275 150);
FORCEPROP 1 LAST OFFPAGE TRUE
J 0
(-3050 100);
DISPLAY 0.872340 (-3050 100);
PAINT AQUA (-3050 100);
DISPLAY INVISIBLE (-3050 100);
FORCEADD OFFPAGE..5
(-3375 75);
FORCEPROP 2 LAST $XR0 31 
J 0
(-3629 75);
DISPLAY 0.638298 (-3629 75);
PAINT MONO (-3629 75);
FORCEPROP 2 LAST PATH I17
J 0
(-3625 125);
DISPLAY 1.021277 (-3625 125);
DISPLAY INVISIBLE (-3625 125);
FORCEPROP 2 LAST CDS_LIB standard
J 0
(-3375 75);
DISPLAY INVISIBLE (-3375 75);
FORCEPROP 1 LAST COMMENT_BODY TRUE
J 0
(-3275 0);
DISPLAY 1.170213 (-3275 0);
PAINT GREEN (-3275 0);
DISPLAY INVISIBLE (-3275 0);
FORCEPROP 1 LAST OFFPAGE TRUE
J 0
(-3050 -50);
DISPLAY 0.872340 (-3050 -50);
PAINT AQUA (-3050 -50);
DISPLAY INVISIBLE (-3050 -50);
FORCEADD OFFPAGE..2
R 2
(-3375 125);
FORCEPROP 2 LAST $XR0 31 
J 0
(-3629 125);
DISPLAY 0.638298 (-3629 125);
PAINT MONO (-3629 125);
FORCEPROP 2 LAST PATH I18
J 0
(-3625 175);
DISPLAY 1.021277 (-3625 175);
DISPLAY INVISIBLE (-3625 175);
FORCEPROP 2 LAST CDS_LIB standard
J 0
(-3375 125);
DISPLAY INVISIBLE (-3375 125);
FORCEPROP 1 LAST COMMENT_BODY TRUE
J 2
(-3330 30);
DISPLAY 0.872340 (-3330 30);
PAINT GREEN (-3330 30);
DISPLAY INVISIBLE (-3330 30);
FORCEPROP 1 LAST OFFPAGE TRUE
J 2
(-3700 0);
DISPLAY 0.872340 (-3700 0);
PAINT AQUA (-3700 0);
DISPLAY INVISIBLE (-3700 0);
FORCEADD UNIVERSAL_GND..1
(-2275 -1475);
FORCEPROP 3 LASTPIN (-2275 -1425) SIG_NAME GND\g
J 0
(-2265 -1415);
DISPLAY 0.659574 (-2265 -1415);
PAINT MONO (-2265 -1415);
DISPLAY INVISIBLE (-2265 -1415);
FORCEPROP 1 LAST PATH I19
J 0
(-2200 -1475);
DISPLAY 0.872340 (-2200 -1475);
PAINT AQUA (-2200 -1475);
DISPLAY INVISIBLE (-2200 -1475);
FORCEPROP 2 LAST CDS_LIB logical_power
J 0
(-2275 -1475);
DISPLAY INVISIBLE (-2275 -1475);
FORCEPROP 1 LAST HDL_POWER GND
J 1
(-2250 -1550);
DISPLAY 0.872340 (-2250 -1550);
PAINT GREEN (-2250 -1550);
DISPLAY INVISIBLE (-2250 -1550);
FORCEADD OFFPAGE..1
(-3375 -1025);
FORCEPROP 2 LAST $XR0 175 
J 0
(-3627 -1025);
DISPLAY 0.638298 (-3627 -1025);
PAINT MONO (-3627 -1025);
FORCEPROP 2 LAST PATH I2
J 0
(-3625 -975);
DISPLAY 1.021277 (-3625 -975);
DISPLAY INVISIBLE (-3625 -975);
FORCEPROP 2 LAST CDS_LIB standard
J 0
(-3375 -1025);
DISPLAY INVISIBLE (-3375 -1025);
FORCEPROP 1 LAST COMMENT_BODY TRUE
J 0
(-3250 -1125);
DISPLAY 0.872340 (-3250 -1125);
PAINT GREEN (-3250 -1125);
DISPLAY INVISIBLE (-3250 -1125);
FORCEPROP 1 LAST OFFPAGE TRUE
J 0
(-3050 -1150);
DISPLAY 0.872340 (-3050 -1150);
PAINT AQUA (-3050 -1150);
DISPLAY INVISIBLE (-3050 -1150);
FORCEADD OFFPAGE..1
(-3375 725);
FORCEPROP 2 LAST $XR0 173 
J 0
(-3627 725);
DISPLAY 0.638298 (-3627 725);
PAINT MONO (-3627 725);
FORCEPROP 2 LAST PATH I20
J 0
(-3625 775);
DISPLAY 1.021277 (-3625 775);
DISPLAY INVISIBLE (-3625 775);
FORCEPROP 2 LAST CDS_LIB standard
J 0
(-3375 725);
DISPLAY INVISIBLE (-3375 725);
FORCEPROP 1 LAST COMMENT_BODY TRUE
J 0
(-3250 625);
DISPLAY 0.872340 (-3250 625);
PAINT GREEN (-3250 625);
DISPLAY INVISIBLE (-3250 625);
FORCEPROP 1 LAST OFFPAGE TRUE
J 0
(-3050 600);
DISPLAY 0.872340 (-3050 600);
PAINT AQUA (-3050 600);
DISPLAY INVISIBLE (-3050 600);
FORCEADD OFFPAGE..1
(-3375 675);
FORCEPROP 2 LAST $XR0 173 
J 0
(-3627 675);
DISPLAY 0.638298 (-3627 675);
PAINT MONO (-3627 675);
FORCEPROP 2 LAST PATH I21
J 0
(-3625 725);
DISPLAY 1.021277 (-3625 725);
DISPLAY INVISIBLE (-3625 725);
FORCEPROP 2 LAST CDS_LIB standard
J 0
(-3375 675);
DISPLAY INVISIBLE (-3375 675);
FORCEPROP 1 LAST OFFPAGE TRUE
J 0
(-3050 550);
DISPLAY 0.872340 (-3050 550);
PAINT AQUA (-3050 550);
DISPLAY INVISIBLE (-3050 550);
FORCEPROP 1 LAST COMMENT_BODY TRUE
J 0
(-3250 575);
DISPLAY 0.872340 (-3250 575);
PAINT GREEN (-3250 575);
DISPLAY INVISIBLE (-3250 575);
FORCEADD OFFPAGE..1
(-3375 575);
FORCEPROP 2 LAST $XR0 175 
J 0
(-3627 575);
DISPLAY 0.638298 (-3627 575);
PAINT MONO (-3627 575);
FORCEPROP 2 LAST PATH I22
J 0
(-3625 625);
DISPLAY 1.021277 (-3625 625);
DISPLAY INVISIBLE (-3625 625);
FORCEPROP 2 LAST CDS_LIB standard
J 0
(-3375 575);
DISPLAY INVISIBLE (-3375 575);
FORCEPROP 1 LAST COMMENT_BODY TRUE
J 0
(-3250 475);
DISPLAY 0.872340 (-3250 475);
PAINT GREEN (-3250 475);
DISPLAY INVISIBLE (-3250 475);
FORCEPROP 1 LAST OFFPAGE TRUE
J 0
(-3050 450);
DISPLAY 0.872340 (-3050 450);
PAINT AQUA (-3050 450);
DISPLAY INVISIBLE (-3050 450);
FORCEADD OFFPAGE..1
(-3375 525);
FORCEPROP 2 LAST $XR0 175 
J 0
(-3627 525);
DISPLAY 0.638298 (-3627 525);
PAINT MONO (-3627 525);
FORCEPROP 2 LAST PATH I23
J 0
(-3625 575);
DISPLAY 1.021277 (-3625 575);
DISPLAY INVISIBLE (-3625 575);
FORCEPROP 2 LAST CDS_LIB standard
J 0
(-3375 525);
DISPLAY INVISIBLE (-3375 525);
FORCEPROP 1 LAST OFFPAGE TRUE
J 0
(-3050 400);
DISPLAY 0.872340 (-3050 400);
PAINT AQUA (-3050 400);
DISPLAY INVISIBLE (-3050 400);
FORCEPROP 1 LAST COMMENT_BODY TRUE
J 0
(-3250 425);
DISPLAY 0.872340 (-3250 425);
PAINT GREEN (-3250 425);
DISPLAY INVISIBLE (-3250 425);
FORCEADD OFFPAGE..5
(-3375 825);
FORCEPROP 2 LAST $XR0 31 
J 0
(-3629 825);
DISPLAY 0.638298 (-3629 825);
PAINT MONO (-3629 825);
FORCEPROP 2 LAST PATH I24
J 0
(-3625 875);
DISPLAY 1.021277 (-3625 875);
DISPLAY INVISIBLE (-3625 875);
FORCEPROP 2 LAST CDS_LIB standard
J 0
(-3375 825);
DISPLAY INVISIBLE (-3375 825);
FORCEPROP 1 LAST OFFPAGE TRUE
J 0
(-3050 700);
DISPLAY 0.872340 (-3050 700);
PAINT AQUA (-3050 700);
DISPLAY INVISIBLE (-3050 700);
FORCEPROP 1 LAST COMMENT_BODY TRUE
J 0
(-3275 750);
DISPLAY 1.170213 (-3275 750);
PAINT GREEN (-3275 750);
DISPLAY INVISIBLE (-3275 750);
FORCEADD OFFPAGE..1
(-3375 1375);
FORCEPROP 2 LAST $XR0 175 
J 0
(-3627 1375);
DISPLAY 0.638298 (-3627 1375);
PAINT MONO (-3627 1375);
FORCEPROP 1 LAST OFFPAGE TRUE
J 0
(-3050 1250);
DISPLAY 0.872340 (-3050 1250);
PAINT AQUA (-3050 1250);
DISPLAY INVISIBLE (-3050 1250);
FORCEPROP 1 LAST COMMENT_BODY TRUE
J 0
(-3250 1275);
DISPLAY 0.872340 (-3250 1275);
PAINT GREEN (-3250 1275);
DISPLAY INVISIBLE (-3250 1275);
FORCEPROP 2 LAST PATH I27
J 0
(-3625 1425);
DISPLAY 1.021277 (-3625 1425);
DISPLAY INVISIBLE (-3625 1425);
FORCEPROP 2 LAST CDS_LIB standard
J 0
(-3375 1375);
DISPLAY INVISIBLE (-3375 1375);
FORCEADD OFFPAGE..2
R 2
(-3375 1025);
FORCEPROP 2 LAST $XR0 29 
J 0
(-3629 1025);
DISPLAY 0.638298 (-3629 1025);
PAINT MONO (-3629 1025);
FORCEPROP 2 LAST CDS_LIB standard
J 0
(-3375 1025);
DISPLAY INVISIBLE (-3375 1025);
FORCEPROP 2 LAST PATH I28
J 0
(-3625 1075);
DISPLAY 1.021277 (-3625 1075);
DISPLAY INVISIBLE (-3625 1075);
FORCEPROP 1 LAST COMMENT_BODY TRUE
J 2
(-3330 930);
DISPLAY 0.872340 (-3330 930);
PAINT GREEN (-3330 930);
DISPLAY INVISIBLE (-3330 930);
FORCEPROP 1 LAST OFFPAGE TRUE
J 2
(-3700 900);
DISPLAY 0.872340 (-3700 900);
PAINT AQUA (-3700 900);
DISPLAY INVISIBLE (-3700 900);
FORCEADD OFFPAGE..5
(-3375 975);
FORCEPROP 2 LAST $XR0 29 
J 0
(-3629 975);
DISPLAY 0.638298 (-3629 975);
PAINT MONO (-3629 975);
FORCEPROP 2 LAST PATH I29
J 0
(-3625 1025);
DISPLAY 1.021277 (-3625 1025);
DISPLAY INVISIBLE (-3625 1025);
FORCEPROP 2 LAST CDS_LIB standard
J 0
(-3375 975);
DISPLAY INVISIBLE (-3375 975);
FORCEPROP 1 LAST OFFPAGE TRUE
J 0
(-3050 850);
DISPLAY 0.872340 (-3050 850);
PAINT AQUA (-3050 850);
DISPLAY INVISIBLE (-3050 850);
FORCEPROP 1 LAST COMMENT_BODY TRUE
J 0
(-3275 900);
DISPLAY 1.170213 (-3275 900);
PAINT GREEN (-3275 900);
DISPLAY INVISIBLE (-3275 900);
FORCEADD OFFPAGE..1
(-3375 -875);
FORCEPROP 2 LAST $XR0 173 
J 0
(-3627 -875);
DISPLAY 0.638298 (-3627 -875);
PAINT MONO (-3627 -875);
FORCEPROP 2 LAST PATH I3
J 0
(-3625 -825);
DISPLAY 1.021277 (-3625 -825);
DISPLAY INVISIBLE (-3625 -825);
FORCEPROP 2 LAST CDS_LIB standard
J 0
(-3375 -875);
DISPLAY INVISIBLE (-3375 -875);
FORCEPROP 1 LAST COMMENT_BODY TRUE
J 0
(-3250 -975);
DISPLAY 0.872340 (-3250 -975);
PAINT GREEN (-3250 -975);
DISPLAY INVISIBLE (-3250 -975);
FORCEPROP 1 LAST OFFPAGE TRUE
J 0
(-3050 -1000);
DISPLAY 0.872340 (-3050 -1000);
PAINT AQUA (-3050 -1000);
DISPLAY INVISIBLE (-3050 -1000);
FORCEADD OFFPAGE..2
R 2
(-3375 875);
FORCEPROP 2 LAST $XR0 31 
J 0
(-3629 875);
DISPLAY 0.638298 (-3629 875);
PAINT MONO (-3629 875);
FORCEPROP 2 LAST PATH I30
J 0
(-3625 925);
DISPLAY 1.021277 (-3625 925);
DISPLAY INVISIBLE (-3625 925);
FORCEPROP 2 LAST CDS_LIB standard
J 0
(-3375 875);
DISPLAY INVISIBLE (-3375 875);
FORCEPROP 1 LAST OFFPAGE TRUE
J 2
(-3700 750);
DISPLAY 0.872340 (-3700 750);
PAINT AQUA (-3700 750);
DISPLAY INVISIBLE (-3700 750);
FORCEPROP 1 LAST COMMENT_BODY TRUE
J 2
(-3330 780);
DISPLAY 0.872340 (-3330 780);
PAINT GREEN (-3330 780);
DISPLAY INVISIBLE (-3330 780);
FORCEADD OFFPAGE..1
(-3375 1575);
FORCEPROP 2 LAST $XR0 173 
J 0
(-3627 1575);
DISPLAY 0.638298 (-3627 1575);
PAINT MONO (-3627 1575);
FORCEPROP 2 LAST PATH I31
J 0
(-3625 1625);
DISPLAY 1.021277 (-3625 1625);
DISPLAY INVISIBLE (-3625 1625);
FORCEPROP 2 LAST CDS_LIB standard
J 0
(-3375 1575);
DISPLAY INVISIBLE (-3375 1575);
FORCEPROP 1 LAST OFFPAGE TRUE
J 0
(-3050 1450);
DISPLAY 0.872340 (-3050 1450);
PAINT AQUA (-3050 1450);
DISPLAY INVISIBLE (-3050 1450);
FORCEPROP 1 LAST COMMENT_BODY TRUE
J 0
(-3250 1475);
DISPLAY 0.872340 (-3250 1475);
PAINT GREEN (-3250 1475);
DISPLAY INVISIBLE (-3250 1475);
FORCEADD OFFPAGE..1
(-3375 1525);
FORCEPROP 2 LAST $XR0 173 
J 0
(-3627 1525);
DISPLAY 0.638298 (-3627 1525);
PAINT MONO (-3627 1525);
FORCEPROP 2 LAST PATH I32
J 0
(-3625 1575);
DISPLAY 1.021277 (-3625 1575);
DISPLAY INVISIBLE (-3625 1575);
FORCEPROP 2 LAST CDS_LIB standard
J 0
(-3375 1525);
DISPLAY INVISIBLE (-3375 1525);
FORCEPROP 1 LAST COMMENT_BODY TRUE
J 0
(-3250 1425);
DISPLAY 0.872340 (-3250 1425);
PAINT GREEN (-3250 1425);
DISPLAY INVISIBLE (-3250 1425);
FORCEPROP 1 LAST OFFPAGE TRUE
J 0
(-3050 1400);
DISPLAY 0.872340 (-3050 1400);
PAINT AQUA (-3050 1400);
DISPLAY INVISIBLE (-3050 1400);
FORCEADD OFFPAGE..1
(-3375 1425);
FORCEPROP 2 LAST $XR0 175 
J 0
(-3627 1425);
DISPLAY 0.638298 (-3627 1425);
PAINT MONO (-3627 1425);
FORCEPROP 2 LAST PATH I33
J 0
(-3625 1475);
DISPLAY 1.021277 (-3625 1475);
DISPLAY INVISIBLE (-3625 1475);
FORCEPROP 2 LAST CDS_LIB standard
J 0
(-3375 1425);
DISPLAY INVISIBLE (-3375 1425);
FORCEPROP 1 LAST OFFPAGE TRUE
J 0
(-3050 1300);
DISPLAY 0.872340 (-3050 1300);
PAINT AQUA (-3050 1300);
DISPLAY INVISIBLE (-3050 1300);
FORCEPROP 1 LAST COMMENT_BODY TRUE
J 0
(-3250 1325);
DISPLAY 0.872340 (-3250 1325);
PAINT GREEN (-3250 1325);
DISPLAY INVISIBLE (-3250 1325);
FORCEADD OFFPAGE..5
(-3375 1825);
FORCEPROP 2 LAST $XR0 29 
J 0
(-3629 1825);
DISPLAY 0.638298 (-3629 1825);
PAINT MONO (-3629 1825);
FORCEPROP 2 LAST PATH I34
J 0
(-3625 1875);
DISPLAY 1.021277 (-3625 1875);
DISPLAY INVISIBLE (-3625 1875);
FORCEPROP 2 LAST CDS_LIB standard
J 0
(-3375 1825);
DISPLAY INVISIBLE (-3375 1825);
FORCEPROP 1 LAST COMMENT_BODY TRUE
J 0
(-3275 1750);
DISPLAY 1.170213 (-3275 1750);
PAINT GREEN (-3275 1750);
DISPLAY INVISIBLE (-3275 1750);
FORCEPROP 1 LAST OFFPAGE TRUE
J 0
(-3050 1700);
DISPLAY 0.872340 (-3050 1700);
PAINT AQUA (-3050 1700);
DISPLAY INVISIBLE (-3050 1700);
FORCEADD OFFPAGE..2
R 2
(-3375 1725);
FORCEPROP 2 LAST $XR0 31 
J 0
(-3629 1725);
DISPLAY 0.638298 (-3629 1725);
PAINT MONO (-3629 1725);
FORCEPROP 2 LAST PATH I35
J 0
(-3625 1775);
DISPLAY 1.021277 (-3625 1775);
DISPLAY INVISIBLE (-3625 1775);
FORCEPROP 2 LAST CDS_LIB standard
J 0
(-3375 1725);
DISPLAY INVISIBLE (-3375 1725);
FORCEPROP 1 LAST OFFPAGE TRUE
J 2
(-3700 1600);
DISPLAY 0.872340 (-3700 1600);
PAINT AQUA (-3700 1600);
DISPLAY INVISIBLE (-3700 1600);
FORCEPROP 1 LAST COMMENT_BODY TRUE
J 2
(-3330 1630);
DISPLAY 0.872340 (-3330 1630);
PAINT GREEN (-3330 1630);
DISPLAY INVISIBLE (-3330 1630);
FORCEADD OFFPAGE..5
(-3375 1675);
FORCEPROP 2 LAST $XR0 31 
J 0
(-3629 1675);
DISPLAY 0.638298 (-3629 1675);
PAINT MONO (-3629 1675);
FORCEPROP 2 LAST PATH I36
J 0
(-3625 1725);
DISPLAY 1.021277 (-3625 1725);
DISPLAY INVISIBLE (-3625 1725);
FORCEPROP 2 LAST CDS_LIB standard
J 0
(-3375 1675);
DISPLAY INVISIBLE (-3375 1675);
FORCEPROP 1 LAST OFFPAGE TRUE
J 0
(-3050 1550);
DISPLAY 0.872340 (-3050 1550);
PAINT AQUA (-3050 1550);
DISPLAY INVISIBLE (-3050 1550);
FORCEPROP 1 LAST COMMENT_BODY TRUE
J 0
(-3275 1600);
DISPLAY 1.170213 (-3275 1600);
PAINT GREEN (-3275 1600);
DISPLAY INVISIBLE (-3275 1600);
FORCEADD OFFPAGE..2
R 2
(-3375 1875);
FORCEPROP 2 LAST $XR0 29 
J 0
(-3629 1875);
DISPLAY 0.638298 (-3629 1875);
PAINT MONO (-3629 1875);
FORCEPROP 2 LAST PATH I37
J 0
(-3625 1925);
DISPLAY 1.021277 (-3625 1925);
DISPLAY INVISIBLE (-3625 1925);
FORCEPROP 2 LAST CDS_LIB standard
J 0
(-3375 1875);
DISPLAY INVISIBLE (-3375 1875);
FORCEPROP 1 LAST COMMENT_BODY TRUE
J 2
(-3330 1780);
DISPLAY 0.872340 (-3330 1780);
PAINT GREEN (-3330 1780);
DISPLAY INVISIBLE (-3330 1780);
FORCEPROP 1 LAST OFFPAGE TRUE
J 2
(-3700 1750);
DISPLAY 0.872340 (-3700 1750);
PAINT AQUA (-3700 1750);
DISPLAY INVISIBLE (-3700 1750);
FORCEADD CONN112_10137002101LF..1
(-1175 425);
FORCEPROP 1 LAST PART_NUMBER DFHSB2FR012
J 0
(-1925 2175);
DISPLAY 0.723404 (-1925 2175);
PAINT GREEN (-1925 2175);
DISPLAY INVISIBLE (-1925 2175);
FORCEPROP 1 LAST MATERIAL IO
J 0
(-1920 2107);
DISPLAY 0.723404 (-1920 2107);
PAINT GREEN (-1920 2107);
FORCEPROP 2 LAST PART_TYPE THLF
J 0
(-1925 2300);
DISPLAY 1.021277 (-1925 2300);
FORCEPROP 1 LAST LOCATION J107
J 0
(-1925 2225);
DISPLAY 0.723404 (-1925 2225);
PAINT GREEN (-1925 2225);
FORCEPROP 0 LASTPIN (-2100 -475) $PN A5
J 2
(-2110 -465);
DISPLAY 0.680851 (-2110 -465);
PAINT MONO (-2110 -465);
FORCEPROP 0 LASTPIN (-2100 325) $PN A6
J 2
(-2110 335);
DISPLAY 0.680851 (-2110 335);
PAINT MONO (-2110 335);
FORCEPROP 0 LASTPIN (-2100 1125) $PN A7
J 2
(-2110 1135);
DISPLAY 0.680851 (-2110 1135);
PAINT MONO (-2110 1135);
FORCEPROP 0 LASTPIN (-2100 1925) $PN A8
J 2
(-2110 1935);
DISPLAY 0.680851 (-2110 1935);
PAINT MONO (-2110 1935);
FORCEPROP 0 LASTPIN (-2100 -525) $PN B5
J 2
(-2110 -515);
DISPLAY 0.680851 (-2110 -515);
PAINT MONO (-2110 -515);
FORCEPROP 0 LASTPIN (-2100 275) $PN B6
J 2
(-2110 285);
DISPLAY 0.680851 (-2110 285);
PAINT MONO (-2110 285);
FORCEPROP 0 LASTPIN (-2100 1075) $PN B7
J 2
(-2110 1085);
DISPLAY 0.680851 (-2110 1085);
PAINT MONO (-2110 1085);
FORCEPROP 0 LASTPIN (-2100 1875) $PN B8
J 2
(-2110 1885);
DISPLAY 0.680851 (-2110 1885);
PAINT MONO (-2110 1885);
FORCEPROP 0 LASTPIN (-2100 -575) $PN C5
J 2
(-2110 -565);
DISPLAY 0.680851 (-2110 -565);
PAINT MONO (-2110 -565);
FORCEPROP 0 LASTPIN (-2100 225) $PN C6
J 2
(-2110 235);
DISPLAY 0.680851 (-2110 235);
PAINT MONO (-2110 235);
FORCEPROP 0 LASTPIN (-2100 1025) $PN C7
J 2
(-2110 1035);
DISPLAY 0.680851 (-2110 1035);
PAINT MONO (-2110 1035);
FORCEPROP 0 LASTPIN (-2100 1825) $PN C8
J 2
(-2110 1835);
DISPLAY 0.680851 (-2110 1835);
PAINT MONO (-2110 1835);
FORCEPROP 0 LASTPIN (-2100 -625) $PN D5
J 2
(-2110 -615);
DISPLAY 0.680851 (-2110 -615);
PAINT MONO (-2110 -615);
FORCEPROP 0 LASTPIN (-2100 175) $PN D6
J 2
(-2110 185);
DISPLAY 0.680851 (-2110 185);
PAINT MONO (-2110 185);
FORCEPROP 0 LASTPIN (-2100 975) $PN D7
J 2
(-2110 985);
DISPLAY 0.680851 (-2110 985);
PAINT MONO (-2110 985);
FORCEPROP 0 LASTPIN (-2100 1775) $PN D8
J 2
(-2110 1785);
DISPLAY 0.680851 (-2110 1785);
PAINT MONO (-2110 1785);
FORCEPROP 0 LASTPIN (-2100 -675) $PN E5
J 2
(-2110 -665);
DISPLAY 0.680851 (-2110 -665);
PAINT MONO (-2110 -665);
FORCEPROP 0 LASTPIN (-2100 125) $PN E6
J 2
(-2110 135);
DISPLAY 0.680851 (-2110 135);
PAINT MONO (-2110 135);
FORCEPROP 0 LASTPIN (-2100 925) $PN E7
J 2
(-2110 935);
DISPLAY 0.680851 (-2110 935);
PAINT MONO (-2110 935);
FORCEPROP 0 LASTPIN (-2100 1725) $PN E8
J 2
(-2110 1735);
DISPLAY 0.680851 (-2110 1735);
PAINT MONO (-2110 1735);
FORCEPROP 0 LASTPIN (-2100 -725) $PN F5
J 2
(-2110 -715);
DISPLAY 0.680851 (-2110 -715);
PAINT MONO (-2110 -715);
FORCEPROP 0 LASTPIN (-2100 75) $PN F6
J 2
(-2110 85);
DISPLAY 0.680851 (-2110 85);
PAINT MONO (-2110 85);
FORCEPROP 0 LASTPIN (-2100 875) $PN F7
J 2
(-2110 885);
DISPLAY 0.680851 (-2110 885);
PAINT MONO (-2110 885);
FORCEPROP 0 LASTPIN (-2100 1675) $PN F8
J 2
(-2110 1685);
DISPLAY 0.680851 (-2110 1685);
PAINT MONO (-2110 1685);
FORCEPROP 0 LASTPIN (-2100 -775) $PN G5
J 2
(-2110 -765);
DISPLAY 0.680851 (-2110 -765);
PAINT MONO (-2110 -765);
FORCEPROP 0 LASTPIN (-2100 25) $PN G6
J 2
(-2110 35);
DISPLAY 0.680851 (-2110 35);
PAINT MONO (-2110 35);
FORCEPROP 0 LASTPIN (-2100 825) $PN G7
J 2
(-2110 835);
DISPLAY 0.680851 (-2110 835);
PAINT MONO (-2110 835);
FORCEPROP 0 LASTPIN (-2100 1625) $PN G8
J 2
(-2110 1635);
DISPLAY 0.680851 (-2110 1635);
PAINT MONO (-2110 1635);
FORCEPROP 0 LASTPIN (-2100 -825) $PN H5
J 2
(-2110 -815);
DISPLAY 0.680851 (-2110 -815);
PAINT MONO (-2110 -815);
FORCEPROP 0 LASTPIN (-2100 -25) $PN H6
J 2
(-2110 -15);
DISPLAY 0.680851 (-2110 -15);
PAINT MONO (-2110 -15);
FORCEPROP 0 LASTPIN (-2100 775) $PN H7
J 2
(-2110 785);
DISPLAY 0.680851 (-2110 785);
PAINT MONO (-2110 785);
FORCEPROP 0 LASTPIN (-2100 1575) $PN H8
J 2
(-2110 1585);
DISPLAY 0.680851 (-2110 1585);
PAINT MONO (-2110 1585);
FORCEPROP 0 LASTPIN (-2100 -875) $PN I5
J 2
(-2110 -865);
DISPLAY 0.680851 (-2110 -865);
PAINT MONO (-2110 -865);
FORCEPROP 0 LASTPIN (-2100 -75) $PN I6
J 2
(-2110 -65);
DISPLAY 0.680851 (-2110 -65);
PAINT MONO (-2110 -65);
FORCEPROP 0 LASTPIN (-2100 725) $PN I7
J 2
(-2110 735);
DISPLAY 0.680851 (-2110 735);
PAINT MONO (-2110 735);
FORCEPROP 0 LASTPIN (-2100 1525) $PN I8
J 2
(-2110 1535);
DISPLAY 0.680851 (-2110 1535);
PAINT MONO (-2110 1535);
FORCEPROP 0 LASTPIN (-2100 -925) $PN J5
J 2
(-2110 -915);
DISPLAY 0.680851 (-2110 -915);
PAINT MONO (-2110 -915);
FORCEPROP 0 LASTPIN (-2100 -125) $PN J6
J 2
(-2110 -115);
DISPLAY 0.680851 (-2110 -115);
PAINT MONO (-2110 -115);
FORCEPROP 0 LASTPIN (-2100 675) $PN J7
J 2
(-2110 685);
DISPLAY 0.680851 (-2110 685);
PAINT MONO (-2110 685);
FORCEPROP 0 LASTPIN (-2100 1475) $PN J8
J 2
(-2110 1485);
DISPLAY 0.680851 (-2110 1485);
PAINT MONO (-2110 1485);
FORCEPROP 0 LASTPIN (-2100 -975) $PN K5
J 2
(-2110 -965);
DISPLAY 0.680851 (-2110 -965);
PAINT MONO (-2110 -965);
FORCEPROP 0 LASTPIN (-2100 -175) $PN K6
J 2
(-2110 -165);
DISPLAY 0.680851 (-2110 -165);
PAINT MONO (-2110 -165);
FORCEPROP 0 LASTPIN (-2100 625) $PN K7
J 2
(-2110 635);
DISPLAY 0.680851 (-2110 635);
PAINT MONO (-2110 635);
FORCEPROP 0 LASTPIN (-2100 1425) $PN K8
J 2
(-2110 1435);
DISPLAY 0.680851 (-2110 1435);
PAINT MONO (-2110 1435);
FORCEPROP 0 LASTPIN (-2100 -1025) $PN L5
J 2
(-2110 -1015);
DISPLAY 0.680851 (-2110 -1015);
PAINT MONO (-2110 -1015);
FORCEPROP 0 LASTPIN (-2100 -225) $PN L6
J 2
(-2110 -215);
DISPLAY 0.680851 (-2110 -215);
PAINT MONO (-2110 -215);
FORCEPROP 0 LASTPIN (-2100 575) $PN L7
J 2
(-2110 585);
DISPLAY 0.680851 (-2110 585);
PAINT MONO (-2110 585);
FORCEPROP 0 LASTPIN (-2100 1375) $PN L8
J 2
(-2110 1385);
DISPLAY 0.680851 (-2110 1385);
PAINT MONO (-2110 1385);
FORCEPROP 0 LASTPIN (-2100 -1075) $PN M5
J 2
(-2110 -1065);
DISPLAY 0.680851 (-2110 -1065);
PAINT MONO (-2110 -1065);
FORCEPROP 0 LASTPIN (-2100 -275) $PN M6
J 2
(-2110 -265);
DISPLAY 0.680851 (-2110 -265);
PAINT MONO (-2110 -265);
FORCEPROP 0 LASTPIN (-2100 525) $PN M7
J 2
(-2110 535);
DISPLAY 0.680851 (-2110 535);
PAINT MONO (-2110 535);
FORCEPROP 0 LASTPIN (-2100 1325) $PN M8
J 2
(-2110 1335);
DISPLAY 0.680851 (-2110 1335);
PAINT MONO (-2110 1335);
FORCEPROP 0 LASTPIN (-2100 -1125) $PN N5
J 2
(-2110 -1115);
DISPLAY 0.680851 (-2110 -1115);
PAINT MONO (-2110 -1115);
FORCEPROP 0 LASTPIN (-2100 -325) $PN N6
J 2
(-2110 -315);
DISPLAY 0.680851 (-2110 -315);
PAINT MONO (-2110 -315);
FORCEPROP 0 LASTPIN (-2100 475) $PN N7
J 2
(-2110 485);
DISPLAY 0.680851 (-2110 485);
PAINT MONO (-2110 485);
FORCEPROP 0 LASTPIN (-2100 1275) $PN N8
J 2
(-2110 1285);
DISPLAY 0.680851 (-2110 1285);
PAINT MONO (-2110 1285);
FORCEPROP 1 LAST PATH I38
J 0
(-1175 425);
DISPLAY 0.723404 (-1175 425);
PAINT GREEN (-1175 425);
DISPLAY INVISIBLE (-1175 425);
FORCEPROP 2 LAST CDS_LIB pure_quanta
J 0
(-1175 425);
DISPLAY INVISIBLE (-1175 425);
FORCEPROP 1 LAST CDS_LMAN_SYM_OUTLINE -775,1650,775,-1650
J 0
(-1175 425);
DISPLAY 0.468085 (-1175 425);
PAINT GREEN (-1175 425);
DISPLAY INVISIBLE (-1175 425);
FORCEPROP 1 LAST NEEDS_NO_SIZE TRUE
J 0
(-1175 425);
DISPLAY 0.723404 (-1175 425);
PAINT GREEN (-1175 425);
DISPLAY INVISIBLE (-1175 425);
FORCEPROP 0 LAST VALUE CONN112_10137002-101LF
J 0
(-1900 2425);
DISPLAY 1.021277 (-1900 2425);
DISPLAY INVISIBLE (-1900 2425);
FORCEPROP 0 LAST $SEC 1
J 0
(-1925 2350);
DISPLAY 0.680851 (-1925 2350);
PAINT MONO (-1925 2350);
DISPLAY INVISIBLE (-1925 2350);
FORCEPROP 0 LAST CDS_SEC 1
J 0
(-1925 2350);
DISPLAY 1.021277 (-1925 2350);
DISPLAY INVISIBLE (-1925 2350);
FORCEADD OFFPAGE..1
(1125 -1025);
FORCEPROP 2 LAST $XR0 175 
J 0
(873 -1025);
DISPLAY 0.638298 (873 -1025);
PAINT MONO (873 -1025);
FORCEPROP 2 LAST PATH I39
J 0
(850 -975);
DISPLAY 1.021277 (850 -975);
DISPLAY INVISIBLE (850 -975);
FORCEPROP 2 LAST CDS_LIB standard
J 0
(1125 -1025);
DISPLAY INVISIBLE (1125 -1025);
FORCEPROP 1 LAST COMMENT_BODY TRUE
J 0
(1250 -1125);
DISPLAY 0.872340 (1250 -1125);
PAINT GREEN (1250 -1125);
DISPLAY INVISIBLE (1250 -1125);
FORCEPROP 1 LAST OFFPAGE TRUE
J 0
(1450 -1150);
DISPLAY 0.872340 (1450 -1150);
PAINT AQUA (1450 -1150);
DISPLAY INVISIBLE (1450 -1150);
FORCEADD OFFPAGE..1
(-3375 -1075);
FORCEPROP 2 LAST $XR0 175 
J 0
(-3627 -1075);
DISPLAY 0.638298 (-3627 -1075);
PAINT MONO (-3627 -1075);
FORCEPROP 2 LAST PATH I4
J 0
(-3625 -1025);
DISPLAY 1.021277 (-3625 -1025);
DISPLAY INVISIBLE (-3625 -1025);
FORCEPROP 2 LAST CDS_LIB standard
J 0
(-3375 -1075);
DISPLAY INVISIBLE (-3375 -1075);
FORCEPROP 1 LAST COMMENT_BODY TRUE
J 0
(-3250 -1175);
DISPLAY 0.872340 (-3250 -1175);
PAINT GREEN (-3250 -1175);
DISPLAY INVISIBLE (-3250 -1175);
FORCEPROP 1 LAST OFFPAGE TRUE
J 0
(-3050 -1200);
DISPLAY 0.872340 (-3050 -1200);
PAINT AQUA (-3050 -1200);
DISPLAY INVISIBLE (-3050 -1200);
FORCEADD OFFPAGE..1
(1125 -1075);
FORCEPROP 2 LAST $XR0 175 
J 0
(873 -1075);
DISPLAY 0.638298 (873 -1075);
PAINT MONO (873 -1075);
FORCEPROP 2 LAST PATH I40
J 0
(850 -1025);
DISPLAY 1.021277 (850 -1025);
DISPLAY INVISIBLE (850 -1025);
FORCEPROP 2 LAST CDS_LIB standard
J 0
(1125 -1075);
DISPLAY INVISIBLE (1125 -1075);
FORCEPROP 1 LAST COMMENT_BODY TRUE
J 0
(1250 -1175);
DISPLAY 0.872340 (1250 -1175);
PAINT GREEN (1250 -1175);
DISPLAY INVISIBLE (1250 -1175);
FORCEPROP 1 LAST OFFPAGE TRUE
J 0
(1450 -1200);
DISPLAY 0.872340 (1450 -1200);
PAINT AQUA (1450 -1200);
DISPLAY INVISIBLE (1450 -1200);
FORCEADD OFFPAGE..1
(1125 -925);
FORCEPROP 2 LAST $XR0 173 
J 0
(873 -925);
DISPLAY 0.638298 (873 -925);
PAINT MONO (873 -925);
FORCEPROP 2 LAST PATH I41
J 0
(850 -875);
DISPLAY 1.021277 (850 -875);
DISPLAY INVISIBLE (850 -875);
FORCEPROP 2 LAST CDS_LIB standard
J 0
(1125 -925);
DISPLAY INVISIBLE (1125 -925);
FORCEPROP 1 LAST OFFPAGE TRUE
J 0
(1450 -1050);
DISPLAY 0.872340 (1450 -1050);
PAINT AQUA (1450 -1050);
DISPLAY INVISIBLE (1450 -1050);
FORCEPROP 1 LAST COMMENT_BODY TRUE
J 0
(1250 -1025);
DISPLAY 0.872340 (1250 -1025);
PAINT GREEN (1250 -1025);
DISPLAY INVISIBLE (1250 -1025);
FORCEADD OFFPAGE..1
(1125 -875);
FORCEPROP 2 LAST $XR0 173 
J 0
(873 -875);
DISPLAY 0.638298 (873 -875);
PAINT MONO (873 -875);
FORCEPROP 2 LAST PATH I42
J 0
(850 -825);
DISPLAY 1.021277 (850 -825);
DISPLAY INVISIBLE (850 -825);
FORCEPROP 2 LAST CDS_LIB standard
J 0
(1125 -875);
DISPLAY INVISIBLE (1125 -875);
FORCEPROP 1 LAST OFFPAGE TRUE
J 0
(1450 -1000);
DISPLAY 0.872340 (1450 -1000);
PAINT AQUA (1450 -1000);
DISPLAY INVISIBLE (1450 -1000);
FORCEPROP 1 LAST COMMENT_BODY TRUE
J 0
(1250 -975);
DISPLAY 0.872340 (1250 -975);
PAINT GREEN (1250 -975);
DISPLAY INVISIBLE (1250 -975);
FORCEADD OFFPAGE..5
(1125 -775);
FORCEPROP 2 LAST $XR0 31 
J 0
(871 -775);
DISPLAY 0.638298 (871 -775);
PAINT MONO (871 -775);
FORCEPROP 2 LAST PATH I43
J 0
(925 -725);
DISPLAY 1.021277 (925 -725);
DISPLAY INVISIBLE (925 -725);
FORCEPROP 2 LAST CDS_LIB standard
J 0
(1125 -775);
DISPLAY INVISIBLE (1125 -775);
FORCEPROP 1 LAST COMMENT_BODY TRUE
J 0
(1225 -850);
DISPLAY 1.170213 (1225 -850);
PAINT GREEN (1225 -850);
DISPLAY INVISIBLE (1225 -850);
FORCEPROP 1 LAST OFFPAGE TRUE
J 0
(1450 -900);
DISPLAY 0.872340 (1450 -900);
PAINT AQUA (1450 -900);
DISPLAY INVISIBLE (1450 -900);
FORCEADD OFFPAGE..2
R 2
(1125 -725);
FORCEPROP 2 LAST $XR0 31 
J 0
(871 -725);
DISPLAY 0.638298 (871 -725);
PAINT MONO (871 -725);
FORCEPROP 2 LAST PATH I44
J 0
(925 -675);
DISPLAY 1.021277 (925 -675);
DISPLAY INVISIBLE (925 -675);
FORCEPROP 2 LAST CDS_LIB standard
J 0
(1125 -725);
DISPLAY INVISIBLE (1125 -725);
FORCEPROP 1 LAST COMMENT_BODY TRUE
J 2
(1170 -820);
DISPLAY 0.872340 (1170 -820);
PAINT GREEN (1170 -820);
DISPLAY INVISIBLE (1170 -820);
FORCEPROP 1 LAST OFFPAGE TRUE
J 2
(800 -850);
DISPLAY 0.872340 (800 -850);
PAINT AQUA (800 -850);
DISPLAY INVISIBLE (800 -850);
FORCEADD OFFPAGE..5
(1125 -625);
FORCEPROP 2 LAST $XR0 29 
J 0
(871 -625);
DISPLAY 0.638298 (871 -625);
PAINT MONO (871 -625);
FORCEPROP 2 LAST PATH I45
J 0
(925 -575);
DISPLAY 1.021277 (925 -575);
DISPLAY INVISIBLE (925 -575);
FORCEPROP 2 LAST CDS_LIB standard
J 0
(1125 -625);
DISPLAY INVISIBLE (1125 -625);
FORCEPROP 1 LAST COMMENT_BODY TRUE
J 0
(1225 -700);
DISPLAY 1.170213 (1225 -700);
PAINT GREEN (1225 -700);
DISPLAY INVISIBLE (1225 -700);
FORCEPROP 1 LAST OFFPAGE TRUE
J 0
(1450 -750);
DISPLAY 0.872340 (1450 -750);
PAINT AQUA (1450 -750);
DISPLAY INVISIBLE (1450 -750);
FORCEADD OFFPAGE..2
R 2
(1125 -575);
FORCEPROP 2 LAST $XR0 29 
J 0
(871 -575);
DISPLAY 0.638298 (871 -575);
PAINT MONO (871 -575);
FORCEPROP 2 LAST CDS_LIB standard
J 0
(1125 -575);
DISPLAY INVISIBLE (1125 -575);
FORCEPROP 2 LAST PATH I46
J 0
(925 -525);
DISPLAY 1.021277 (925 -525);
DISPLAY INVISIBLE (925 -525);
FORCEPROP 1 LAST OFFPAGE TRUE
J 2
(800 -700);
DISPLAY 0.872340 (800 -700);
PAINT AQUA (800 -700);
DISPLAY INVISIBLE (800 -700);
FORCEPROP 1 LAST COMMENT_BODY TRUE
J 2
(1170 -670);
DISPLAY 0.872340 (1170 -670);
PAINT GREEN (1170 -670);
DISPLAY INVISIBLE (1170 -670);
FORCEADD OFFPAGE..1
(1125 -225);
FORCEPROP 2 LAST $XR0 175 
J 0
(873 -225);
DISPLAY 0.638298 (873 -225);
PAINT MONO (873 -225);
FORCEPROP 2 LAST PATH I49
J 0
(850 -175);
DISPLAY 1.021277 (850 -175);
DISPLAY INVISIBLE (850 -175);
FORCEPROP 2 LAST CDS_LIB standard
J 0
(1125 -225);
DISPLAY INVISIBLE (1125 -225);
FORCEPROP 1 LAST OFFPAGE TRUE
J 0
(1450 -350);
DISPLAY 0.872340 (1450 -350);
PAINT AQUA (1450 -350);
DISPLAY INVISIBLE (1450 -350);
FORCEPROP 1 LAST COMMENT_BODY TRUE
J 0
(1250 -325);
DISPLAY 0.872340 (1250 -325);
PAINT GREEN (1250 -325);
DISPLAY INVISIBLE (1250 -325);
FORCEADD OFFPAGE..5
(-3375 -775);
FORCEPROP 2 LAST $XR0 31 
J 0
(-3629 -775);
DISPLAY 0.638298 (-3629 -775);
PAINT MONO (-3629 -775);
FORCEPROP 2 LAST PATH I5
J 0
(-3625 -725);
DISPLAY 1.021277 (-3625 -725);
DISPLAY INVISIBLE (-3625 -725);
FORCEPROP 2 LAST CDS_LIB standard
J 0
(-3375 -775);
DISPLAY INVISIBLE (-3375 -775);
FORCEPROP 1 LAST OFFPAGE TRUE
J 0
(-3050 -900);
DISPLAY 0.872340 (-3050 -900);
PAINT AQUA (-3050 -900);
DISPLAY INVISIBLE (-3050 -900);
FORCEPROP 1 LAST COMMENT_BODY TRUE
J 0
(-3275 -850);
DISPLAY 1.170213 (-3275 -850);
PAINT GREEN (-3275 -850);
DISPLAY INVISIBLE (-3275 -850);
FORCEADD OFFPAGE..1
(1125 -175);
FORCEPROP 2 LAST $XR0 175 
J 0
(873 -175);
DISPLAY 0.638298 (873 -175);
PAINT MONO (873 -175);
FORCEPROP 2 LAST PATH I50
J 0
(850 -125);
DISPLAY 1.021277 (850 -125);
DISPLAY INVISIBLE (850 -125);
FORCEPROP 2 LAST CDS_LIB standard
J 0
(1125 -175);
DISPLAY INVISIBLE (1125 -175);
FORCEPROP 1 LAST OFFPAGE TRUE
J 0
(1450 -300);
DISPLAY 0.872340 (1450 -300);
PAINT AQUA (1450 -300);
DISPLAY INVISIBLE (1450 -300);
FORCEPROP 1 LAST COMMENT_BODY TRUE
J 0
(1250 -275);
DISPLAY 0.872340 (1250 -275);
PAINT GREEN (1250 -275);
DISPLAY INVISIBLE (1250 -275);
FORCEADD OFFPAGE..5
(1125 75);
FORCEPROP 2 LAST $XR0 31 
J 0
(871 75);
DISPLAY 0.638298 (871 75);
PAINT MONO (871 75);
FORCEPROP 2 LAST PATH I51
J 0
(925 125);
DISPLAY 1.021277 (925 125);
DISPLAY INVISIBLE (925 125);
FORCEPROP 2 LAST CDS_LIB standard
J 0
(1125 75);
DISPLAY INVISIBLE (1125 75);
FORCEPROP 1 LAST OFFPAGE TRUE
J 0
(1450 -50);
DISPLAY 0.872340 (1450 -50);
PAINT AQUA (1450 -50);
DISPLAY INVISIBLE (1450 -50);
FORCEPROP 1 LAST COMMENT_BODY TRUE
J 0
(1225 0);
DISPLAY 1.170213 (1225 0);
PAINT GREEN (1225 0);
DISPLAY INVISIBLE (1225 0);
FORCEADD OFFPAGE..1
(1125 -25);
FORCEPROP 2 LAST $XR0 173 
J 0
(873 -25);
DISPLAY 0.638298 (873 -25);
PAINT MONO (873 -25);
FORCEPROP 2 LAST PATH I52
J 0
(850 25);
DISPLAY 1.021277 (850 25);
DISPLAY INVISIBLE (850 25);
FORCEPROP 2 LAST CDS_LIB standard
J 0
(1125 -25);
DISPLAY INVISIBLE (1125 -25);
FORCEPROP 1 LAST COMMENT_BODY TRUE
J 0
(1250 -125);
DISPLAY 0.872340 (1250 -125);
PAINT GREEN (1250 -125);
DISPLAY INVISIBLE (1250 -125);
FORCEPROP 1 LAST OFFPAGE TRUE
J 0
(1450 -150);
DISPLAY 0.872340 (1450 -150);
PAINT AQUA (1450 -150);
DISPLAY INVISIBLE (1450 -150);
FORCEADD OFFPAGE..1
(1125 -75);
FORCEPROP 2 LAST $XR0 173 
J 0
(873 -75);
DISPLAY 0.638298 (873 -75);
PAINT MONO (873 -75);
FORCEPROP 2 LAST PATH I53
J 0
(850 -25);
DISPLAY 1.021277 (850 -25);
DISPLAY INVISIBLE (850 -25);
FORCEPROP 2 LAST CDS_LIB standard
J 0
(1125 -75);
DISPLAY INVISIBLE (1125 -75);
FORCEPROP 1 LAST COMMENT_BODY TRUE
J 0
(1250 -175);
DISPLAY 0.872340 (1250 -175);
PAINT GREEN (1250 -175);
DISPLAY INVISIBLE (1250 -175);
FORCEPROP 1 LAST OFFPAGE TRUE
J 0
(1450 -200);
DISPLAY 0.872340 (1450 -200);
PAINT AQUA (1450 -200);
DISPLAY INVISIBLE (1450 -200);
FORCEADD OFFPAGE..2
R 2
(1125 125);
FORCEPROP 2 LAST $XR0 31 
J 0
(871 125);
DISPLAY 0.638298 (871 125);
PAINT MONO (871 125);
FORCEPROP 2 LAST PATH I54
J 0
(925 175);
DISPLAY 1.021277 (925 175);
DISPLAY INVISIBLE (925 175);
FORCEPROP 2 LAST CDS_LIB standard
J 0
(1125 125);
DISPLAY INVISIBLE (1125 125);
FORCEPROP 1 LAST OFFPAGE TRUE
J 2
(800 0);
DISPLAY 0.872340 (800 0);
PAINT AQUA (800 0);
DISPLAY INVISIBLE (800 0);
FORCEPROP 1 LAST COMMENT_BODY TRUE
J 2
(1170 30);
DISPLAY 0.872340 (1170 30);
PAINT GREEN (1170 30);
DISPLAY INVISIBLE (1170 30);
FORCEADD OFFPAGE..5
(1125 225);
FORCEPROP 2 LAST $XR0 29 
J 0
(871 225);
DISPLAY 0.638298 (871 225);
PAINT MONO (871 225);
FORCEPROP 2 LAST PATH I55
J 0
(925 275);
DISPLAY 1.021277 (925 275);
DISPLAY INVISIBLE (925 275);
FORCEPROP 2 LAST CDS_LIB standard
J 0
(1125 225);
DISPLAY INVISIBLE (1125 225);
FORCEPROP 1 LAST COMMENT_BODY TRUE
J 0
(1225 150);
DISPLAY 1.170213 (1225 150);
PAINT GREEN (1225 150);
DISPLAY INVISIBLE (1225 150);
FORCEPROP 1 LAST OFFPAGE TRUE
J 0
(1450 100);
DISPLAY 0.872340 (1450 100);
PAINT AQUA (1450 100);
DISPLAY INVISIBLE (1450 100);
FORCEADD OFFPAGE..2
R 2
(1125 275);
FORCEPROP 2 LAST $XR0 29 
J 0
(871 275);
DISPLAY 0.638298 (871 275);
PAINT MONO (871 275);
FORCEPROP 2 LAST PATH I56
J 0
(925 325);
DISPLAY 1.021277 (925 325);
DISPLAY INVISIBLE (925 325);
FORCEPROP 2 LAST CDS_LIB standard
J 0
(1125 275);
DISPLAY INVISIBLE (1125 275);
FORCEPROP 1 LAST COMMENT_BODY TRUE
J 2
(1170 180);
DISPLAY 0.872340 (1170 180);
PAINT GREEN (1170 180);
DISPLAY INVISIBLE (1170 180);
FORCEPROP 1 LAST OFFPAGE TRUE
J 2
(800 150);
DISPLAY 0.872340 (800 150);
PAINT AQUA (800 150);
DISPLAY INVISIBLE (800 150);
FORCEADD UNIVERSAL_GND..1
(2175 -1525);
FORCEPROP 3 LASTPIN (2175 -1475) SIG_NAME GND\g
J 0
(2185 -1465);
DISPLAY 0.659574 (2185 -1465);
PAINT MONO (2185 -1465);
DISPLAY INVISIBLE (2185 -1465);
FORCEPROP 1 LAST PATH I57
J 0
(2250 -1525);
DISPLAY 0.872340 (2250 -1525);
PAINT AQUA (2250 -1525);
DISPLAY INVISIBLE (2250 -1525);
FORCEPROP 2 LAST CDS_LIB logical_power
J 0
(2175 -1525);
DISPLAY INVISIBLE (2175 -1525);
FORCEPROP 1 LAST HDL_POWER GND
J 1
(2200 -1600);
DISPLAY 0.872340 (2200 -1600);
PAINT GREEN (2200 -1600);
DISPLAY INVISIBLE (2200 -1600);
FORCEADD CONN112_10137002101LF..2
(3325 425);
FORCEPROP 1 LAST PART_NUMBER DFHSB2FR012
J 0
(2575 2200);
DISPLAY 0.723404 (2575 2200);
PAINT GREEN (2575 2200);
DISPLAY INVISIBLE (2575 2200);
FORCEPROP 2 LAST PART_TYPE THLF
J 0
(2575 2325);
DISPLAY 1.021277 (2575 2325);
FORCEPROP 1 LAST MATERIAL IO
J 0
(2583 2138);
DISPLAY 0.723404 (2583 2138);
PAINT GREEN (2583 2138);
FORCEPROP 1 LAST LOCATION J107
J 0
(2575 2250);
DISPLAY 0.723404 (2575 2250);
PAINT GREEN (2575 2250);
FORCEPROP 0 LASTPIN (2400 -475) $PN A1
J 2
(2390 -465);
DISPLAY 0.680851 (2390 -465);
PAINT MONO (2390 -465);
FORCEPROP 0 LASTPIN (2400 325) $PN A2
J 2
(2390 335);
DISPLAY 0.680851 (2390 335);
PAINT MONO (2390 335);
FORCEPROP 0 LASTPIN (2400 1125) $PN A3
J 2
(2390 1135);
DISPLAY 0.680851 (2390 1135);
PAINT MONO (2390 1135);
FORCEPROP 0 LASTPIN (2400 1925) $PN A4
J 2
(2390 1935);
DISPLAY 0.680851 (2390 1935);
PAINT MONO (2390 1935);
FORCEPROP 0 LASTPIN (2400 -525) $PN B1
J 2
(2390 -515);
DISPLAY 0.680851 (2390 -515);
PAINT MONO (2390 -515);
FORCEPROP 0 LASTPIN (2400 275) $PN B2
J 2
(2390 285);
DISPLAY 0.680851 (2390 285);
PAINT MONO (2390 285);
FORCEPROP 0 LASTPIN (2400 1075) $PN B3
J 2
(2390 1085);
DISPLAY 0.680851 (2390 1085);
PAINT MONO (2390 1085);
FORCEPROP 0 LASTPIN (2400 1875) $PN B4
J 2
(2390 1885);
DISPLAY 0.680851 (2390 1885);
PAINT MONO (2390 1885);
FORCEPROP 0 LASTPIN (2400 -575) $PN C1
J 2
(2390 -565);
DISPLAY 0.680851 (2390 -565);
PAINT MONO (2390 -565);
FORCEPROP 0 LASTPIN (2400 225) $PN C2
J 2
(2390 235);
DISPLAY 0.680851 (2390 235);
PAINT MONO (2390 235);
FORCEPROP 0 LASTPIN (2400 1025) $PN C3
J 2
(2390 1035);
DISPLAY 0.680851 (2390 1035);
PAINT MONO (2390 1035);
FORCEPROP 0 LASTPIN (2400 1825) $PN C4
J 2
(2390 1835);
DISPLAY 0.680851 (2390 1835);
PAINT MONO (2390 1835);
FORCEPROP 0 LASTPIN (2400 -625) $PN D1
J 2
(2390 -615);
DISPLAY 0.680851 (2390 -615);
PAINT MONO (2390 -615);
FORCEPROP 0 LASTPIN (2400 175) $PN D2
J 2
(2390 185);
DISPLAY 0.680851 (2390 185);
PAINT MONO (2390 185);
FORCEPROP 0 LASTPIN (2400 975) $PN D3
J 2
(2390 985);
DISPLAY 0.680851 (2390 985);
PAINT MONO (2390 985);
FORCEPROP 0 LASTPIN (2400 1775) $PN D4
J 2
(2390 1785);
DISPLAY 0.680851 (2390 1785);
PAINT MONO (2390 1785);
FORCEPROP 0 LASTPIN (2400 -675) $PN E1
J 2
(2390 -665);
DISPLAY 0.680851 (2390 -665);
PAINT MONO (2390 -665);
FORCEPROP 0 LASTPIN (2400 125) $PN E2
J 2
(2390 135);
DISPLAY 0.680851 (2390 135);
PAINT MONO (2390 135);
FORCEPROP 0 LASTPIN (2400 925) $PN E3
J 2
(2390 935);
DISPLAY 0.680851 (2390 935);
PAINT MONO (2390 935);
FORCEPROP 0 LASTPIN (2400 1725) $PN E4
J 2
(2390 1735);
DISPLAY 0.680851 (2390 1735);
PAINT MONO (2390 1735);
FORCEPROP 0 LASTPIN (2400 -725) $PN F1
J 2
(2390 -715);
DISPLAY 0.680851 (2390 -715);
PAINT MONO (2390 -715);
FORCEPROP 0 LASTPIN (2400 75) $PN F2
J 2
(2390 85);
DISPLAY 0.680851 (2390 85);
PAINT MONO (2390 85);
FORCEPROP 0 LASTPIN (2400 875) $PN F3
J 2
(2390 885);
DISPLAY 0.680851 (2390 885);
PAINT MONO (2390 885);
FORCEPROP 0 LASTPIN (2400 1675) $PN F4
J 2
(2390 1685);
DISPLAY 0.680851 (2390 1685);
PAINT MONO (2390 1685);
FORCEPROP 0 LASTPIN (2400 -775) $PN G1
J 2
(2390 -765);
DISPLAY 0.680851 (2390 -765);
PAINT MONO (2390 -765);
FORCEPROP 0 LASTPIN (2400 25) $PN G2
J 2
(2390 35);
DISPLAY 0.680851 (2390 35);
PAINT MONO (2390 35);
FORCEPROP 0 LASTPIN (2400 825) $PN G3
J 2
(2390 835);
DISPLAY 0.680851 (2390 835);
PAINT MONO (2390 835);
FORCEPROP 0 LASTPIN (2400 1625) $PN G4
J 2
(2390 1635);
DISPLAY 0.680851 (2390 1635);
PAINT MONO (2390 1635);
FORCEPROP 0 LASTPIN (2400 -825) $PN H1
J 2
(2390 -815);
DISPLAY 0.680851 (2390 -815);
PAINT MONO (2390 -815);
FORCEPROP 0 LASTPIN (2400 -25) $PN H2
J 2
(2390 -15);
DISPLAY 0.680851 (2390 -15);
PAINT MONO (2390 -15);
FORCEPROP 0 LASTPIN (2400 775) $PN H3
J 2
(2390 785);
DISPLAY 0.680851 (2390 785);
PAINT MONO (2390 785);
FORCEPROP 0 LASTPIN (2400 1575) $PN H4
J 2
(2390 1585);
DISPLAY 0.680851 (2390 1585);
PAINT MONO (2390 1585);
FORCEPROP 0 LASTPIN (2400 -875) $PN I1
J 2
(2390 -865);
DISPLAY 0.680851 (2390 -865);
PAINT MONO (2390 -865);
FORCEPROP 0 LASTPIN (2400 -75) $PN I2
J 2
(2390 -65);
DISPLAY 0.680851 (2390 -65);
PAINT MONO (2390 -65);
FORCEPROP 0 LASTPIN (2400 725) $PN I3
J 2
(2390 735);
DISPLAY 0.680851 (2390 735);
PAINT MONO (2390 735);
FORCEPROP 0 LASTPIN (2400 1525) $PN I4
J 2
(2390 1535);
DISPLAY 0.680851 (2390 1535);
PAINT MONO (2390 1535);
FORCEPROP 0 LASTPIN (2400 -925) $PN J1
J 2
(2390 -915);
DISPLAY 0.680851 (2390 -915);
PAINT MONO (2390 -915);
FORCEPROP 0 LASTPIN (2400 -125) $PN J2
J 2
(2390 -115);
DISPLAY 0.680851 (2390 -115);
PAINT MONO (2390 -115);
FORCEPROP 0 LASTPIN (2400 675) $PN J3
J 2
(2390 685);
DISPLAY 0.680851 (2390 685);
PAINT MONO (2390 685);
FORCEPROP 0 LASTPIN (2400 1475) $PN J4
J 2
(2390 1485);
DISPLAY 0.680851 (2390 1485);
PAINT MONO (2390 1485);
FORCEPROP 0 LASTPIN (2400 -975) $PN K1
J 2
(2390 -965);
DISPLAY 0.680851 (2390 -965);
PAINT MONO (2390 -965);
FORCEPROP 0 LASTPIN (2400 -175) $PN K2
J 2
(2390 -165);
DISPLAY 0.680851 (2390 -165);
PAINT MONO (2390 -165);
FORCEPROP 0 LASTPIN (2400 625) $PN K3
J 2
(2390 635);
DISPLAY 0.680851 (2390 635);
PAINT MONO (2390 635);
FORCEPROP 0 LASTPIN (2400 1425) $PN K4
J 2
(2390 1435);
DISPLAY 0.680851 (2390 1435);
PAINT MONO (2390 1435);
FORCEPROP 0 LASTPIN (2400 -1025) $PN L1
J 2
(2390 -1015);
DISPLAY 0.680851 (2390 -1015);
PAINT MONO (2390 -1015);
FORCEPROP 0 LASTPIN (2400 -225) $PN L2
J 2
(2390 -215);
DISPLAY 0.680851 (2390 -215);
PAINT MONO (2390 -215);
FORCEPROP 0 LASTPIN (2400 575) $PN L3
J 2
(2390 585);
DISPLAY 0.680851 (2390 585);
PAINT MONO (2390 585);
FORCEPROP 0 LASTPIN (2400 1375) $PN L4
J 2
(2390 1385);
DISPLAY 0.680851 (2390 1385);
PAINT MONO (2390 1385);
FORCEPROP 0 LASTPIN (2400 -1075) $PN M1
J 2
(2390 -1065);
DISPLAY 0.680851 (2390 -1065);
PAINT MONO (2390 -1065);
FORCEPROP 0 LASTPIN (2400 -275) $PN M2
J 2
(2390 -265);
DISPLAY 0.680851 (2390 -265);
PAINT MONO (2390 -265);
FORCEPROP 0 LASTPIN (2400 525) $PN M3
J 2
(2390 535);
DISPLAY 0.680851 (2390 535);
PAINT MONO (2390 535);
FORCEPROP 0 LASTPIN (2400 1325) $PN M4
J 2
(2390 1335);
DISPLAY 0.680851 (2390 1335);
PAINT MONO (2390 1335);
FORCEPROP 0 LASTPIN (2400 -1125) $PN N1
J 2
(2390 -1115);
DISPLAY 0.680851 (2390 -1115);
PAINT MONO (2390 -1115);
FORCEPROP 0 LASTPIN (2400 -325) $PN N2
J 2
(2390 -315);
DISPLAY 0.680851 (2390 -315);
PAINT MONO (2390 -315);
FORCEPROP 0 LASTPIN (2400 475) $PN N3
J 2
(2390 485);
DISPLAY 0.680851 (2390 485);
PAINT MONO (2390 485);
FORCEPROP 0 LASTPIN (2400 1275) $PN N4
J 2
(2390 1285);
DISPLAY 0.680851 (2390 1285);
PAINT MONO (2390 1285);
FORCEPROP 1 LAST PATH I58
J 0
(3325 425);
DISPLAY 0.723404 (3325 425);
PAINT GREEN (3325 425);
DISPLAY INVISIBLE (3325 425);
FORCEPROP 2 LAST CDS_LIB pure_quanta
J 0
(3325 425);
DISPLAY INVISIBLE (3325 425);
FORCEPROP 1 LAST CDS_LMAN_SYM_OUTLINE -775,1650,775,-1650
J 0
(3325 425);
DISPLAY 0.468085 (3325 425);
PAINT GREEN (3325 425);
DISPLAY INVISIBLE (3325 425);
FORCEPROP 0 LAST VALUE CONN112_10137002-101LF
J 0
(2575 2325);
DISPLAY 1.021277 (2575 2325);
DISPLAY INVISIBLE (2575 2325);
FORCEPROP 1 LAST NEEDS_NO_SIZE TRUE
J 0
(3325 425);
DISPLAY 0.723404 (3325 425);
PAINT GREEN (3325 425);
DISPLAY INVISIBLE (3325 425);
FORCEPROP 0 LAST $SEC 2
J 0
(2575 2375);
DISPLAY 0.680851 (2575 2375);
PAINT MONO (2575 2375);
DISPLAY INVISIBLE (2575 2375);
FORCEPROP 0 LAST CDS_SEC 2
J 0
(2575 2375);
DISPLAY 1.021277 (2575 2375);
DISPLAY INVISIBLE (2575 2375);
FORCEADD OFFPAGE..1
(1100 575);
FORCEPROP 2 LAST $XR0 175 
J 0
(848 575);
DISPLAY 0.638298 (848 575);
PAINT MONO (848 575);
FORCEPROP 2 LAST PATH I59
J 0
(825 625);
DISPLAY 1.021277 (825 625);
DISPLAY INVISIBLE (825 625);
FORCEPROP 2 LAST CDS_LIB standard
J 0
(1100 575);
DISPLAY INVISIBLE (1100 575);
FORCEPROP 1 LAST COMMENT_BODY TRUE
J 0
(1225 475);
DISPLAY 0.872340 (1225 475);
PAINT GREEN (1225 475);
DISPLAY INVISIBLE (1225 475);
FORCEPROP 1 LAST OFFPAGE TRUE
J 0
(1425 450);
DISPLAY 0.872340 (1425 450);
PAINT AQUA (1425 450);
DISPLAY INVISIBLE (1425 450);
FORCEADD OFFPAGE..2
R 2
(-3375 -725);
FORCEPROP 2 LAST $XR0 31 
J 0
(-3629 -725);
DISPLAY 0.638298 (-3629 -725);
PAINT MONO (-3629 -725);
FORCEPROP 2 LAST PATH I6
J 0
(-3625 -675);
DISPLAY 1.021277 (-3625 -675);
DISPLAY INVISIBLE (-3625 -675);
FORCEPROP 2 LAST CDS_LIB standard
J 0
(-3375 -725);
DISPLAY INVISIBLE (-3375 -725);
FORCEPROP 1 LAST OFFPAGE TRUE
J 2
(-3700 -850);
DISPLAY 0.872340 (-3700 -850);
PAINT AQUA (-3700 -850);
DISPLAY INVISIBLE (-3700 -850);
FORCEPROP 1 LAST COMMENT_BODY TRUE
J 2
(-3330 -820);
DISPLAY 0.872340 (-3330 -820);
PAINT GREEN (-3330 -820);
DISPLAY INVISIBLE (-3330 -820);
FORCEADD OFFPAGE..1
(1100 525);
FORCEPROP 2 LAST $XR0 175 
J 0
(848 525);
DISPLAY 0.638298 (848 525);
PAINT MONO (848 525);
FORCEPROP 2 LAST PATH I60
J 0
(825 575);
DISPLAY 1.021277 (825 575);
DISPLAY INVISIBLE (825 575);
FORCEPROP 2 LAST CDS_LIB standard
J 0
(1100 525);
DISPLAY INVISIBLE (1100 525);
FORCEPROP 1 LAST OFFPAGE TRUE
J 0
(1425 400);
DISPLAY 0.872340 (1425 400);
PAINT AQUA (1425 400);
DISPLAY INVISIBLE (1425 400);
FORCEPROP 1 LAST COMMENT_BODY TRUE
J 0
(1225 425);
DISPLAY 0.872340 (1225 425);
PAINT GREEN (1225 425);
DISPLAY INVISIBLE (1225 425);
FORCEADD OFFPAGE..5
(1100 825);
FORCEPROP 2 LAST $XR0 31 
J 0
(876 825);
DISPLAY 0.638298 (876 825);
PAINT MONO (876 825);
FORCEPROP 2 LAST PATH I61
J 0
(850 875);
DISPLAY 1.021277 (850 875);
DISPLAY INVISIBLE (850 875);
FORCEPROP 2 LAST CDS_LIB standard
J 0
(1100 825);
DISPLAY INVISIBLE (1100 825);
FORCEPROP 1 LAST COMMENT_BODY TRUE
J 0
(1200 750);
DISPLAY 1.170213 (1200 750);
PAINT GREEN (1200 750);
DISPLAY INVISIBLE (1200 750);
FORCEPROP 1 LAST OFFPAGE TRUE
J 0
(1425 700);
DISPLAY 0.872340 (1425 700);
PAINT AQUA (1425 700);
DISPLAY INVISIBLE (1425 700);
FORCEADD OFFPAGE..1
(1100 725);
FORCEPROP 2 LAST $XR0 173 
J 0
(848 725);
DISPLAY 0.638298 (848 725);
PAINT MONO (848 725);
FORCEPROP 2 LAST PATH I62
J 0
(825 775);
DISPLAY 1.021277 (825 775);
DISPLAY INVISIBLE (825 775);
FORCEPROP 2 LAST CDS_LIB standard
J 0
(1100 725);
DISPLAY INVISIBLE (1100 725);
FORCEPROP 1 LAST COMMENT_BODY TRUE
J 0
(1225 625);
DISPLAY 0.872340 (1225 625);
PAINT GREEN (1225 625);
DISPLAY INVISIBLE (1225 625);
FORCEPROP 1 LAST OFFPAGE TRUE
J 0
(1425 600);
DISPLAY 0.872340 (1425 600);
PAINT AQUA (1425 600);
DISPLAY INVISIBLE (1425 600);
FORCEADD OFFPAGE..1
(1100 675);
FORCEPROP 2 LAST $XR0 173 
J 0
(848 675);
DISPLAY 0.638298 (848 675);
PAINT MONO (848 675);
FORCEPROP 2 LAST PATH I63
J 0
(825 725);
DISPLAY 1.021277 (825 725);
DISPLAY INVISIBLE (825 725);
FORCEPROP 2 LAST CDS_LIB standard
J 0
(1100 675);
DISPLAY INVISIBLE (1100 675);
FORCEPROP 1 LAST OFFPAGE TRUE
J 0
(1425 550);
DISPLAY 0.872340 (1425 550);
PAINT AQUA (1425 550);
DISPLAY INVISIBLE (1425 550);
FORCEPROP 1 LAST COMMENT_BODY TRUE
J 0
(1225 575);
DISPLAY 0.872340 (1225 575);
PAINT GREEN (1225 575);
DISPLAY INVISIBLE (1225 575);
FORCEADD OFFPAGE..2
R 2
(1100 875);
FORCEPROP 2 LAST $XR0 31 
J 0
(876 875);
DISPLAY 0.638298 (876 875);
PAINT MONO (876 875);
FORCEPROP 2 LAST PATH I64
J 0
(850 925);
DISPLAY 1.021277 (850 925);
DISPLAY INVISIBLE (850 925);
FORCEPROP 2 LAST CDS_LIB standard
J 0
(1100 875);
DISPLAY INVISIBLE (1100 875);
FORCEPROP 1 LAST COMMENT_BODY TRUE
J 2
(1145 780);
DISPLAY 0.872340 (1145 780);
PAINT GREEN (1145 780);
DISPLAY INVISIBLE (1145 780);
FORCEPROP 1 LAST OFFPAGE TRUE
J 2
(775 750);
DISPLAY 0.872340 (775 750);
PAINT AQUA (775 750);
DISPLAY INVISIBLE (775 750);
FORCEADD OFFPAGE..5
(1100 975);
FORCEPROP 2 LAST $XR0 29 
J 0
(876 975);
DISPLAY 0.638298 (876 975);
PAINT MONO (876 975);
FORCEPROP 2 LAST PATH I65
J 0
(850 1025);
DISPLAY 1.021277 (850 1025);
DISPLAY INVISIBLE (850 1025);
FORCEPROP 2 LAST CDS_LIB standard
J 0
(1100 975);
DISPLAY INVISIBLE (1100 975);
FORCEPROP 1 LAST COMMENT_BODY TRUE
J 0
(1200 900);
DISPLAY 1.170213 (1200 900);
PAINT GREEN (1200 900);
DISPLAY INVISIBLE (1200 900);
FORCEPROP 1 LAST OFFPAGE TRUE
J 0
(1425 850);
DISPLAY 0.872340 (1425 850);
PAINT AQUA (1425 850);
DISPLAY INVISIBLE (1425 850);
FORCEADD OFFPAGE..2
R 2
(1100 1025);
FORCEPROP 2 LAST $XR0 29 
J 0
(876 1025);
DISPLAY 0.638298 (876 1025);
PAINT MONO (876 1025);
FORCEPROP 2 LAST PATH I66
J 0
(850 1075);
DISPLAY 1.021277 (850 1075);
DISPLAY INVISIBLE (850 1075);
FORCEPROP 2 LAST CDS_LIB standard
J 0
(1100 1025);
DISPLAY INVISIBLE (1100 1025);
FORCEPROP 1 LAST COMMENT_BODY TRUE
J 2
(1145 930);
DISPLAY 0.872340 (1145 930);
PAINT GREEN (1145 930);
DISPLAY INVISIBLE (1145 930);
FORCEPROP 1 LAST OFFPAGE TRUE
J 2
(775 900);
DISPLAY 0.872340 (775 900);
PAINT AQUA (775 900);
DISPLAY INVISIBLE (775 900);
FORCEADD OFFPAGE..1
(1100 1375);
FORCEPROP 2 LAST $XR0 175 
J 0
(848 1375);
DISPLAY 0.638298 (848 1375);
PAINT MONO (848 1375);
FORCEPROP 2 LAST PATH I69
J 0
(825 1425);
DISPLAY 1.021277 (825 1425);
DISPLAY INVISIBLE (825 1425);
FORCEPROP 2 LAST CDS_LIB standard
J 0
(1100 1375);
DISPLAY INVISIBLE (1100 1375);
FORCEPROP 1 LAST OFFPAGE TRUE
J 0
(1425 1250);
DISPLAY 0.872340 (1425 1250);
PAINT AQUA (1425 1250);
DISPLAY INVISIBLE (1425 1250);
FORCEPROP 1 LAST COMMENT_BODY TRUE
J 0
(1225 1275);
DISPLAY 0.872340 (1225 1275);
PAINT GREEN (1225 1275);
DISPLAY INVISIBLE (1225 1275);
FORCEADD OFFPAGE..1
(1100 1575);
FORCEPROP 2 LAST $XR0 173 
J 0
(848 1575);
DISPLAY 0.638298 (848 1575);
PAINT MONO (848 1575);
FORCEPROP 2 LAST PATH I70
J 0
(825 1625);
DISPLAY 1.021277 (825 1625);
DISPLAY INVISIBLE (825 1625);
FORCEPROP 2 LAST CDS_LIB standard
J 0
(1100 1575);
DISPLAY INVISIBLE (1100 1575);
FORCEPROP 1 LAST OFFPAGE TRUE
J 0
(1425 1450);
DISPLAY 0.872340 (1425 1450);
PAINT AQUA (1425 1450);
DISPLAY INVISIBLE (1425 1450);
FORCEPROP 1 LAST COMMENT_BODY TRUE
J 0
(1225 1475);
DISPLAY 0.872340 (1225 1475);
PAINT GREEN (1225 1475);
DISPLAY INVISIBLE (1225 1475);
FORCEADD OFFPAGE..1
(1100 1525);
FORCEPROP 2 LAST $XR0 173 
J 0
(848 1525);
DISPLAY 0.638298 (848 1525);
PAINT MONO (848 1525);
FORCEPROP 2 LAST PATH I71
J 0
(825 1575);
DISPLAY 1.021277 (825 1575);
DISPLAY INVISIBLE (825 1575);
FORCEPROP 2 LAST CDS_LIB standard
J 0
(1100 1525);
DISPLAY INVISIBLE (1100 1525);
FORCEPROP 1 LAST COMMENT_BODY TRUE
J 0
(1225 1425);
DISPLAY 0.872340 (1225 1425);
PAINT GREEN (1225 1425);
DISPLAY INVISIBLE (1225 1425);
FORCEPROP 1 LAST OFFPAGE TRUE
J 0
(1425 1400);
DISPLAY 0.872340 (1425 1400);
PAINT AQUA (1425 1400);
DISPLAY INVISIBLE (1425 1400);
FORCEADD OFFPAGE..1
(1100 1425);
FORCEPROP 2 LAST $XR0 175 
J 0
(848 1425);
DISPLAY 0.638298 (848 1425);
PAINT MONO (848 1425);
FORCEPROP 2 LAST PATH I72
J 0
(825 1475);
DISPLAY 1.021277 (825 1475);
DISPLAY INVISIBLE (825 1475);
FORCEPROP 2 LAST CDS_LIB standard
J 0
(1100 1425);
DISPLAY INVISIBLE (1100 1425);
FORCEPROP 1 LAST COMMENT_BODY TRUE
J 0
(1225 1325);
DISPLAY 0.872340 (1225 1325);
PAINT GREEN (1225 1325);
DISPLAY INVISIBLE (1225 1325);
FORCEPROP 1 LAST OFFPAGE TRUE
J 0
(1425 1300);
DISPLAY 0.872340 (1425 1300);
PAINT AQUA (1425 1300);
DISPLAY INVISIBLE (1425 1300);
FORCEADD OFFPAGE..2
R 2
(1100 1725);
FORCEPROP 2 LAST $XR0 31 
J 0
(876 1725);
DISPLAY 0.638298 (876 1725);
PAINT MONO (876 1725);
FORCEPROP 2 LAST PATH I73
J 0
(850 1775);
DISPLAY 1.021277 (850 1775);
DISPLAY INVISIBLE (850 1775);
FORCEPROP 2 LAST CDS_LIB standard
J 0
(1100 1725);
DISPLAY INVISIBLE (1100 1725);
FORCEPROP 1 LAST OFFPAGE TRUE
J 2
(775 1600);
DISPLAY 0.872340 (775 1600);
PAINT AQUA (775 1600);
DISPLAY INVISIBLE (775 1600);
FORCEPROP 1 LAST COMMENT_BODY TRUE
J 2
(1145 1630);
DISPLAY 0.872340 (1145 1630);
PAINT GREEN (1145 1630);
DISPLAY INVISIBLE (1145 1630);
FORCEADD OFFPAGE..5
(1100 1675);
FORCEPROP 2 LAST $XR0 31 
J 0
(876 1675);
DISPLAY 0.638298 (876 1675);
PAINT MONO (876 1675);
FORCEPROP 2 LAST PATH I74
J 0
(850 1725);
DISPLAY 1.021277 (850 1725);
DISPLAY INVISIBLE (850 1725);
FORCEPROP 2 LAST CDS_LIB standard
J 0
(1100 1675);
DISPLAY INVISIBLE (1100 1675);
FORCEPROP 1 LAST OFFPAGE TRUE
J 0
(1425 1550);
DISPLAY 0.872340 (1425 1550);
PAINT AQUA (1425 1550);
DISPLAY INVISIBLE (1425 1550);
FORCEPROP 1 LAST COMMENT_BODY TRUE
J 0
(1200 1600);
DISPLAY 1.170213 (1200 1600);
PAINT GREEN (1200 1600);
DISPLAY INVISIBLE (1200 1600);
FORCEADD OFFPAGE..2
R 2
(1100 1875);
FORCEPROP 2 LAST $XR0 29 
J 0
(876 1875);
DISPLAY 0.638298 (876 1875);
PAINT MONO (876 1875);
FORCEPROP 2 LAST PATH I75
J 0
(850 1925);
DISPLAY 1.021277 (850 1925);
DISPLAY INVISIBLE (850 1925);
FORCEPROP 2 LAST CDS_LIB standard
J 0
(1100 1875);
DISPLAY INVISIBLE (1100 1875);
FORCEPROP 1 LAST COMMENT_BODY TRUE
J 2
(1145 1780);
DISPLAY 0.872340 (1145 1780);
PAINT GREEN (1145 1780);
DISPLAY INVISIBLE (1145 1780);
FORCEPROP 1 LAST OFFPAGE TRUE
J 2
(775 1750);
DISPLAY 0.872340 (775 1750);
PAINT AQUA (775 1750);
DISPLAY INVISIBLE (775 1750);
FORCEADD OFFPAGE..5
(1100 1825);
FORCEPROP 2 LAST $XR0 29 
J 0
(876 1825);
DISPLAY 0.638298 (876 1825);
PAINT MONO (876 1825);
FORCEPROP 2 LAST PATH I76
J 0
(850 1875);
DISPLAY 1.021277 (850 1875);
DISPLAY INVISIBLE (850 1875);
FORCEPROP 2 LAST CDS_LIB standard
J 0
(1100 1825);
DISPLAY INVISIBLE (1100 1825);
FORCEPROP 1 LAST COMMENT_BODY TRUE
J 0
(1200 1750);
DISPLAY 1.170213 (1200 1750);
PAINT GREEN (1200 1750);
DISPLAY INVISIBLE (1200 1750);
FORCEPROP 1 LAST OFFPAGE TRUE
J 0
(1425 1700);
DISPLAY 0.872340 (1425 1700);
PAINT AQUA (1425 1700);
DISPLAY INVISIBLE (1425 1700);
FORCEADD OFFPAGE..1
(-3375 1275);
FORCEPROP 2 LAST $XR0 145 
J 0
(-3627 1275);
DISPLAY 0.638298 (-3627 1275);
PAINT MONO (-3627 1275);
FORCEPROP 2 LAST PATH I77
J 0
(-3325 1350);
DISPLAY 1.021277 (-3325 1350);
DISPLAY INVISIBLE (-3325 1350);
FORCEPROP 1 LAST COMMENT_BODY TRUE
J 0
(-3250 1175);
DISPLAY 0.872340 (-3250 1175);
PAINT GREEN (-3250 1175);
DISPLAY INVISIBLE (-3250 1175);
FORCEPROP 1 LAST OFFPAGE TRUE
J 0
(-3050 1150);
DISPLAY 0.872340 (-3050 1150);
PAINT AQUA (-3050 1150);
DISPLAY INVISIBLE (-3050 1150);
FORCEPROP 2 LAST CDS_LIB standard
J 0
(-3375 1275);
DISPLAY INVISIBLE (-3375 1275);
FORCEADD OFFPAGE..2
R 2
(-3375 1125);
FORCEPROP 2 LAST $XR0 146 
J 0
(-3660 1125);
DISPLAY 0.638298 (-3660 1125);
PAINT MONO (-3660 1125);
FORCEPROP 2 LAST PATH I78
J 0
(-3325 1200);
DISPLAY 1.021277 (-3325 1200);
DISPLAY INVISIBLE (-3325 1200);
FORCEPROP 1 LAST COMMENT_BODY TRUE
J 2
(-3330 1030);
DISPLAY 0.872340 (-3330 1030);
PAINT GREEN (-3330 1030);
DISPLAY INVISIBLE (-3330 1030);
FORCEPROP 1 LAST OFFPAGE TRUE
J 2
(-3700 1000);
DISPLAY 0.872340 (-3700 1000);
PAINT AQUA (-3700 1000);
DISPLAY INVISIBLE (-3700 1000);
FORCEPROP 2 LAST CDS_LIB standard
J 0
(-3375 1125);
DISPLAY INVISIBLE (-3375 1125);
FORCEADD OFFPAGE..2
R 2
(1125 -325);
FORCEPROP 2 LAST $XR0 144 
J 0
(840 -325);
DISPLAY 0.638298 (840 -325);
PAINT MONO (840 -325);
FORCEPROP 1 LAST COMMENT_BODY TRUE
J 2
(1170 -420);
DISPLAY 0.872340 (1170 -420);
PAINT GREEN (1170 -420);
DISPLAY INVISIBLE (1170 -420);
FORCEPROP 1 LAST OFFPAGE TRUE
J 2
(800 -450);
DISPLAY 0.872340 (800 -450);
PAINT AQUA (800 -450);
DISPLAY INVISIBLE (800 -450);
FORCEPROP 2 LAST PATH I79
J 0
(1175 -250);
DISPLAY 1.021277 (1175 -250);
DISPLAY INVISIBLE (1175 -250);
FORCEPROP 2 LAST CDS_LIB standard
J 0
(1125 -325);
DISPLAY INVISIBLE (1125 -325);
FORCEADD OFFPAGE..1
(-3375 -225);
FORCEPROP 2 LAST $XR0 175 
J 0
(-3627 -225);
DISPLAY 0.638298 (-3627 -225);
PAINT MONO (-3627 -225);
FORCEPROP 2 LAST PATH I8
J 0
(-3625 -175);
DISPLAY 1.021277 (-3625 -175);
DISPLAY INVISIBLE (-3625 -175);
FORCEPROP 2 LAST CDS_LIB standard
J 0
(-3375 -225);
DISPLAY INVISIBLE (-3375 -225);
FORCEPROP 1 LAST COMMENT_BODY TRUE
J 0
(-3250 -325);
DISPLAY 0.872340 (-3250 -325);
PAINT GREEN (-3250 -325);
DISPLAY INVISIBLE (-3250 -325);
FORCEPROP 1 LAST OFFPAGE TRUE
J 0
(-3050 -350);
DISPLAY 0.872340 (-3050 -350);
PAINT AQUA (-3050 -350);
DISPLAY INVISIBLE (-3050 -350);
FORCEADD OFFPAGE..2
R 2
(-3375 -575);
FORCEPROP 2 LAST $XR0 29 
J 0
(-3629 -575);
DISPLAY 0.638298 (-3629 -575);
PAINT MONO (-3629 -575);
FORCEPROP 2 LAST PATH I9
J 0
(-3625 -525);
DISPLAY 1.021277 (-3625 -525);
DISPLAY INVISIBLE (-3625 -525);
FORCEPROP 2 LAST CDS_LIB standard
J 0
(-3375 -575);
DISPLAY INVISIBLE (-3375 -575);
FORCEPROP 1 LAST OFFPAGE TRUE
J 2
(-3700 -700);
DISPLAY 0.872340 (-3700 -700);
PAINT AQUA (-3700 -700);
DISPLAY INVISIBLE (-3700 -700);
FORCEPROP 1 LAST COMMENT_BODY TRUE
J 2
(-3330 -670);
DISPLAY 0.872340 (-3330 -670);
PAINT GREEN (-3330 -670);
DISPLAY INVISIBLE (-3330 -670);
FORCEADD QUANTA_TITLE_BLOCK_C..1
(4700 -3400);
FORCEPROP 0 LAST CDS_CON_LAST_MODIFIED Fri Aug 25 14:01:59 2023
J 0
(2815 -3385);
PAINT MONO (2815 -3385);
DISPLAY INVISIBLE (2815 -3385);
FORCEPROP 2 LAST CUSTOM_TXT_CDS <XR_PAGE_TITLE>
J 0
(-3190 1850);
DISPLAY 0.638298 (-3190 1850);
PAINT PINK (-3190 1850);
DISPLAY INVISIBLE (-3190 1850);
FORCEPROP 2 LAST CUSTOM_TXT_CDS <CON_LAST_MODIFIED>
J 0
(2825 -3400);
DISPLAY 0.978723 (2825 -3400);
FORCEPROP 2 LAST CUSTOM_TXT_CDS <Q_PROJ>
J 0
(2318 -3298);
DISPLAY 1.212766 (2318 -3298);
FORCEPROP 2 LAST CUSTOM_TXT_CDS <NAME_1>
J 0
(1525 -3225);
FORCEPROP 2 LAST CUSTOM_TXT_CDS <NAME_2>
J 0
(1525 -3350);
FORCEPROP 2 LAST CUSTOM_TXT_CDS <Q_REV>
J 0
(4516 -3297);
DISPLAY 1.212766 (4516 -3297);
FORCEPROP 2 LAST CUSTOM_TXT_CDS <Q_NUMBER>
J 0
(3297 -3297);
DISPLAY 1.212766 (3297 -3297);
FORCEPROP 1 LAST CUSTOM_TXT_CDS <CON_PAGE_NUM> OF <CON_TOTAL_PAGES>
J 0
(4254 -3382);
DISPLAY 0.978723 (4254 -3382);
FORCEPROP 1 LAST Q_TITLE PCIE - CPU0_EXAMAX_P0/P4_X16
J 0
(-4575 -3350);
DISPLAY 1.957447 (-4575 -3350);
PAINT GREEN (-4575 -3350);
FORCEPROP 1 LAST Q_DEPT 
J 1
(937 -3351);
DISPLAY 1.957447 (937 -3351);
PAINT GREEN (937 -3351);
FORCEPROP 2 LAST CDS_XR_PAGE_TITLE CR-138 : @S9S_MB_2U_LIB.S9S_MB_2U(SCH_1):PAGE138
J 0
(-3190 1850);
DISPLAY 0.638298 (-3190 1850);
PAINT PINK (-3190 1850);
DISPLAY INVISIBLE (-3190 1850);
FORCEPROP 1 LAST CDS_LMAN_SYM_OUTLINE -9475,6775,100,-125
J 0
(4700 -3400);
DISPLAY 0.468085 (4700 -3400);
PAINT GREEN (4700 -3400);
DISPLAY INVISIBLE (4700 -3400);
FORCEPROP 2 LAST CDS_LIB pure_quanta
J 0
(4700 -3400);
PAINT MONO (4700 -3400);
DISPLAY INVISIBLE (4700 -3400);
FORCEPROP 1 LAST COMMENT_BODY TRUE
J 0
(4712 -3413);
DISPLAY 0.978723 (4712 -3413);
PAINT GREEN (4712 -3413);
DISPLAY INVISIBLE (4712 -3413);
FORCEPROP 2 LAST PAGE_BORDER TRUE
J 0
(-3190 1850);
DISPLAY 0.638298 (-3190 1850);
PAINT PINK (-3190 1850);
DISPLAY INVISIBLE (-3190 1850);
WIRE 16 -1 (-2275 -1125)(-2275 -1425);
WIRE 16 -1 (-2275 -975)(-2275 -1125);
WIRE 16 -1 (-2100 -1125)(-2275 -1125);
WIRE 16 -1 (2175 -1125)(2175 -1475);
WIRE 16 -1 (2175 -975)(2175 -1125);
WIRE 16 -1 (2400 -1125)(2175 -1125);
WIRE 16 -1 (2400 -325)(1175 -325);
FORCEPROP 2 LAST SIG_NAME PRSNT_CABLE_SWB_B2_N
J 0
(1340 -315);
DISPLAY 0.638298 (1340 -315);
WIRE 16 -1 (2400 -475)(1175 -475);
FORCEPROP 2 LAST SIG_NAME NC_J107_A1
J 0
(1340 -465);
DISPLAY 0.638298 (1340 -465);
WIRE 16 -1 (2400 1925)(2175 1925);
WIRE 16 -1 (2175 1925)(2175 1775);
WIRE 16 -1 (2400 1775)(2175 1775);
WIRE 16 -1 (2175 1775)(2175 1625);
WIRE 16 -1 (2400 1625)(2175 1625);
WIRE 16 -1 (2400 1475)(2175 1475);
WIRE 16 -1 (2175 1625)(2175 1475);
WIRE 16 -1 (2175 1475)(2175 1325);
WIRE 16 -1 (2400 1325)(2175 1325);
WIRE 16 -1 (2175 1325)(2175 1075);
WIRE 16 -1 (2400 1075)(2175 1075);
WIRE 16 -1 (2400 925)(2175 925);
WIRE 16 -1 (2175 1075)(2175 925);
WIRE 16 -1 (2175 925)(2175 775);
WIRE 16 -1 (2400 775)(2175 775);
WIRE 16 -1 (2175 775)(2175 625);
WIRE 16 -1 (2400 625)(2175 625);
WIRE 16 -1 (2400 475)(2175 475);
WIRE 16 -1 (2175 625)(2175 475);
WIRE 16 -1 (2175 475)(2175 325);
WIRE 16 -1 (2400 325)(2175 325);
WIRE 16 -1 (2175 325)(2175 175);
WIRE 16 -1 (2400 175)(2175 175);
WIRE 16 -1 (2175 175)(2175 25);
WIRE 16 -1 (2400 25)(2175 25);
WIRE 16 -1 (2400 -125)(2175 -125);
WIRE 16 -1 (2175 25)(2175 -125);
WIRE 16 -1 (2175 -125)(2175 -275);
WIRE 16 -1 (2400 -275)(2175 -275);
WIRE 16 -1 (2400 -525)(2175 -525);
WIRE 16 -1 (2175 -275)(2175 -525);
WIRE 16 -1 (2175 -525)(2175 -675);
WIRE 16 -1 (2400 -675)(2175 -675);
WIRE 16 -1 (2175 -675)(2175 -825);
WIRE 16 -1 (2400 -825)(2175 -825);
WIRE 16 -1 (2175 -825)(2175 -975);
WIRE 16 -1 (2400 -975)(2175 -975);
WIRE 16 -1 (2400 -575)(1175 -575);
FORCEPROP 2 LAST SIG_NAME P5E_CPU0_PE0_RX_DN<7>
J 0
(1315 -565);
DISPLAY 0.638298 (1315 -565);
WIRE 16 -1 (2400 -625)(1175 -625);
FORCEPROP 2 LAST SIG_NAME P5E_CPU0_PE0_RX_DP<7>
J 0
(1315 -615);
DISPLAY 0.638298 (1315 -615);
WIRE 16 -1 (2400 -725)(1175 -725);
FORCEPROP 2 LAST SIG_NAME P5E_CPU0_PE4_RX_DN<8>
J 0
(1315 -715);
DISPLAY 0.638298 (1315 -715);
WIRE 16 -1 (2400 -775)(1175 -775);
FORCEPROP 2 LAST SIG_NAME P5E_CPU0_PE4_RX_DP<8>
J 0
(1315 -765);
DISPLAY 0.638298 (1315 -765);
WIRE 16 -1 (2400 -225)(1175 -225);
FORCEPROP 2 LAST SIG_NAME P5E_CPU0_PE4_TX_C_DP<9>
J 0
(1315 -215);
DISPLAY 0.638298 (1315 -215);
WIRE 16 -1 (2400 -175)(1175 -175);
FORCEPROP 2 LAST SIG_NAME P5E_CPU0_PE4_TX_C_DN<9>
J 0
(1315 -165);
DISPLAY 0.638298 (1315 -165);
WIRE 16 -1 (-2100 -975)(-2275 -975);
WIRE 16 -1 (-2275 -825)(-2275 -975);
WIRE 16 -1 (-2100 -825)(-2275 -825);
WIRE 16 -1 (-2275 -825)(-2275 -675);
WIRE 16 -1 (-2100 -675)(-2275 -675);
WIRE 16 -1 (-2275 -675)(-2275 -525);
WIRE 16 -1 (-2100 -525)(-2275 -525);
WIRE 16 -1 (-2275 -275)(-2275 -525);
WIRE 16 -1 (-2100 -275)(-2275 -275);
WIRE 16 -1 (-2275 -125)(-2275 -275);
WIRE 16 -1 (-2100 -125)(-2275 -125);
WIRE 16 -1 (-2275 25)(-2275 -125);
WIRE 16 -1 (-2100 25)(-2275 25);
WIRE 16 -1 (-2275 175)(-2275 25);
WIRE 16 -1 (-2100 175)(-2275 175);
WIRE 16 -1 (-2275 325)(-2275 175);
WIRE 16 -1 (-2100 325)(-2275 325);
WIRE 16 -1 (-2275 475)(-2275 325);
WIRE 16 -1 (-2100 475)(-2275 475);
WIRE 16 -1 (-2275 625)(-2275 475);
WIRE 16 -1 (-2100 625)(-2275 625);
WIRE 16 -1 (-2275 775)(-2275 625);
WIRE 16 -1 (-2100 775)(-2275 775);
WIRE 16 -1 (-2275 925)(-2275 775);
WIRE 16 -1 (-2100 925)(-2275 925);
WIRE 16 -1 (-2275 1075)(-2275 925);
WIRE 16 -1 (-2100 1075)(-2275 1075);
WIRE 16 -1 (-2275 1325)(-2275 1075);
WIRE 16 -1 (-2100 1325)(-2275 1325);
WIRE 16 -1 (-2275 1475)(-2275 1325);
WIRE 16 -1 (-2100 1475)(-2275 1475);
WIRE 16 -1 (-2275 1625)(-2275 1475);
WIRE 16 -1 (-2100 1625)(-2275 1625);
WIRE 16 -1 (-2275 1775)(-2275 1625);
WIRE 16 -1 (-2100 1775)(-2275 1775);
WIRE 16 -1 (-2275 1925)(-2275 1775);
WIRE 16 -1 (-2100 1925)(-2275 1925);
WIRE 16 -1 (-2100 1025)(-3325 1025);
FORCEPROP 2 LAST SIG_NAME P5E_CPU0_PE0_RX_DP<1>
J 0
(-3160 1035);
DISPLAY 0.638298 (-3160 1035);
WIRE 16 -1 (-2100 1125)(-3325 1125);
FORCEPROP 2 LAST SIG_NAME SWB_HSC_PWRGD
J 0
(-3160 1135);
DISPLAY 0.638298 (-3160 1135);
WIRE 16 -1 (-2100 1275)(-3325 1275);
FORCEPROP 2 LAST SIG_NAME SWB_HSC_EN_BUF
J 0
(-3160 1285);
DISPLAY 0.638298 (-3160 1285);
WIRE 16 -1 (-2100 975)(-3325 975);
FORCEPROP 2 LAST SIG_NAME P5E_CPU0_PE0_RX_DN<1>
J 0
(-3160 985);
DISPLAY 0.638298 (-3160 985);
WIRE 16 -1 (-2100 875)(-3325 875);
FORCEPROP 2 LAST SIG_NAME P5E_CPU0_PE4_RX_DN<14>
J 0
(-3160 885);
DISPLAY 0.638298 (-3160 885);
WIRE 16 -1 (-2100 825)(-3325 825);
FORCEPROP 2 LAST SIG_NAME P5E_CPU0_PE4_RX_DP<14>
J 0
(-3160 835);
DISPLAY 0.638298 (-3160 835);
WIRE 16 -1 (-2100 725)(-3325 725);
FORCEPROP 2 LAST SIG_NAME P5E_CPU0_PE0_TX_C_DN<1>
J 0
(-3160 735);
DISPLAY 0.638298 (-3160 735);
WIRE 16 -1 (-2100 675)(-3325 675);
FORCEPROP 2 LAST SIG_NAME P5E_CPU0_PE0_TX_C_DP<1>
J 0
(-3160 685);
DISPLAY 0.638298 (-3160 685);
WIRE 16 -1 (-2100 75)(-3325 75);
FORCEPROP 2 LAST SIG_NAME P5E_CPU0_PE4_RX_DN<13>
J 0
(-3160 85);
DISPLAY 0.638298 (-3160 85);
WIRE 16 -1 (-2100 -625)(-3325 -625);
FORCEPROP 2 LAST SIG_NAME P5E_CPU0_PE0_RX_DN<3>
J 0
(-3160 -615);
DISPLAY 0.638298 (-3160 -615);
WIRE 16 -1 (-2100 -475)(-3325 -475);
FORCEPROP 2 LAST SIG_NAME NC_J107_A5
J 0
(-3160 -465);
DISPLAY 0.638298 (-3160 -465);
WIRE 16 -1 (-2100 -325)(-3325 -325);
FORCEPROP 2 LAST SIG_NAME NC_J107_N6
J 0
(-3160 -315);
DISPLAY 0.638298 (-3160 -315);
WIRE 16 -1 (-2100 275)(-3325 275);
FORCEPROP 2 LAST SIG_NAME P5E_CPU0_PE0_RX_DN<2>
J 0
(-3160 285);
DISPLAY 0.638298 (-3160 285);
WIRE 16 -1 (-2100 575)(-3325 575);
FORCEPROP 2 LAST SIG_NAME P5E_CPU0_PE4_TX_C_DN<14>
J 0
(-3160 585);
DISPLAY 0.638298 (-3160 585);
WIRE 16 -1 (-2100 1575)(-3325 1575);
FORCEPROP 2 LAST SIG_NAME P5E_CPU0_PE0_TX_C_DN<0>
J 0
(-3160 1585);
DISPLAY 0.638298 (-3160 1585);
WIRE 16 -1 (-2100 1675)(-3325 1675);
FORCEPROP 2 LAST SIG_NAME P5E_CPU0_PE4_RX_DN<15>
J 0
(-3160 1685);
DISPLAY 0.638298 (-3160 1685);
WIRE 16 -1 (-2100 1825)(-3325 1825);
FORCEPROP 2 LAST SIG_NAME P5E_CPU0_PE0_RX_DP<0>
J 0
(-3160 1835);
DISPLAY 0.638298 (-3160 1835);
WIRE 16 -1 (-2100 1875)(-3325 1875);
FORCEPROP 2 LAST SIG_NAME P5E_CPU0_PE0_RX_DN<0>
J 0
(-3160 1885);
DISPLAY 0.638298 (-3160 1885);
WIRE 16 -1 (-2100 1375)(-3325 1375);
FORCEPROP 2 LAST SIG_NAME P5E_CPU0_PE4_TX_C_DP<15>
J 0
(-3160 1385);
DISPLAY 0.638298 (-3160 1385);
WIRE 16 -1 (-2100 1525)(-3325 1525);
FORCEPROP 2 LAST SIG_NAME P5E_CPU0_PE0_TX_C_DP<0>
J 0
(-3160 1535);
DISPLAY 0.638298 (-3160 1535);
WIRE 16 -1 (-2100 1425)(-3325 1425);
FORCEPROP 2 LAST SIG_NAME P5E_CPU0_PE4_TX_C_DN<15>
J 0
(-3160 1435);
DISPLAY 0.638298 (-3160 1435);
WIRE 16 -1 (-2100 1725)(-3325 1725);
FORCEPROP 2 LAST SIG_NAME P5E_CPU0_PE4_RX_DP<15>
J 0
(-3160 1735);
DISPLAY 0.638298 (-3160 1735);
WIRE 16 -1 (2400 1125)(1175 1125);
FORCEPROP 2 LAST SIG_NAME NC_J107_A3
J 0
(1340 1135);
DISPLAY 0.638298 (1340 1135);
WIRE 16 -1 (2400 975)(1150 975);
FORCEPROP 2 LAST SIG_NAME P5E_CPU0_PE0_RX_DP<5>
J 0
(1315 985);
DISPLAY 0.638298 (1315 985);
WIRE 16 -1 (2400 875)(1150 875);
FORCEPROP 2 LAST SIG_NAME P5E_CPU0_PE4_RX_DN<10>
J 0
(1315 885);
DISPLAY 0.638298 (1315 885);
WIRE 16 -1 (2400 825)(1150 825);
FORCEPROP 2 LAST SIG_NAME P5E_CPU0_PE4_RX_DP<10>
J 0
(1315 835);
DISPLAY 0.638298 (1315 835);
WIRE 16 -1 (2400 675)(1150 675);
FORCEPROP 2 LAST SIG_NAME P5E_CPU0_PE0_TX_C_DP<5>
J 0
(1315 685);
DISPLAY 0.638298 (1315 685);
WIRE 16 -1 (2400 525)(1150 525);
FORCEPROP 2 LAST SIG_NAME P5E_CPU0_PE4_TX_C_DP<10>
J 0
(1315 535);
DISPLAY 0.638298 (1315 535);
WIRE 16 -1 (2400 275)(1175 275);
FORCEPROP 2 LAST SIG_NAME P5E_CPU0_PE0_RX_DN<6>
J 0
(1315 285);
DISPLAY 0.638298 (1315 285);
WIRE 16 -1 (2400 225)(1175 225);
FORCEPROP 2 LAST SIG_NAME P5E_CPU0_PE0_RX_DP<6>
J 0
(1315 235);
DISPLAY 0.638298 (1315 235);
WIRE 16 -1 (2400 -75)(1175 -75);
FORCEPROP 2 LAST SIG_NAME P5E_CPU0_PE0_TX_C_DP<6>
J 0
(1315 -65);
DISPLAY 0.638298 (1315 -65);
WIRE 16 -1 (2400 -875)(1175 -875);
FORCEPROP 2 LAST SIG_NAME P5E_CPU0_PE0_TX_C_DN<7>
J 0
(1315 -865);
DISPLAY 0.638298 (1315 -865);
WIRE 16 -1 (2400 -925)(1175 -925);
FORCEPROP 2 LAST SIG_NAME P5E_CPU0_PE0_TX_C_DP<7>
J 0
(1315 -915);
DISPLAY 0.638298 (1315 -915);
WIRE 16 -1 (2400 -25)(1175 -25);
FORCEPROP 2 LAST SIG_NAME P5E_CPU0_PE0_TX_C_DN<6>
J 0
(1315 -15);
DISPLAY 0.638298 (1315 -15);
WIRE 16 -1 (2400 125)(1175 125);
FORCEPROP 2 LAST SIG_NAME P5E_CPU0_PE4_RX_DP<9>
J 0
(1315 135);
DISPLAY 0.638298 (1315 135);
WIRE 16 -1 (2400 75)(1175 75);
FORCEPROP 2 LAST SIG_NAME P5E_CPU0_PE4_RX_DN<9>
J 0
(1315 85);
DISPLAY 0.638298 (1315 85);
WIRE 16 -1 (2400 725)(1150 725);
FORCEPROP 2 LAST SIG_NAME P5E_CPU0_PE0_TX_C_DN<5>
J 0
(1315 735);
DISPLAY 0.638298 (1315 735);
WIRE 16 -1 (-2100 -1025)(-3325 -1025);
FORCEPROP 2 LAST SIG_NAME P5E_CPU0_PE4_TX_C_DN<12>
J 0
(-3160 -1015);
DISPLAY 0.638298 (-3160 -1015);
WIRE 16 -1 (-2100 -775)(-3325 -775);
FORCEPROP 2 LAST SIG_NAME P5E_CPU0_PE4_RX_DP<12>
J 0
(-3160 -765);
DISPLAY 0.638298 (-3160 -765);
WIRE 16 -1 (-2100 -925)(-3325 -925);
FORCEPROP 2 LAST SIG_NAME P5E_CPU0_PE0_TX_C_DP<3>
J 0
(-3160 -915);
DISPLAY 0.638298 (-3160 -915);
WIRE 16 -1 (2400 1275)(1175 1275);
FORCEPROP 2 LAST SIG_NAME NC_J107_N4
J 0
(1340 1285);
DISPLAY 0.638298 (1340 1285);
WIRE 16 -1 (-2100 525)(-3325 525);
FORCEPROP 2 LAST SIG_NAME P5E_CPU0_PE4_TX_C_DP<14>
J 0
(-3160 535);
DISPLAY 0.638298 (-3160 535);
WIRE 16 -1 (2400 1525)(1150 1525);
FORCEPROP 2 LAST SIG_NAME P5E_CPU0_PE0_TX_C_DP<4>
J 0
(1315 1535);
DISPLAY 0.638298 (1315 1535);
WIRE 16 -1 (2400 1375)(1150 1375);
FORCEPROP 2 LAST SIG_NAME P5E_CPU0_PE4_TX_C_DN<11>
J 0
(1315 1385);
DISPLAY 0.638298 (1315 1385);
WIRE 16 -1 (2400 -1075)(1175 -1075);
FORCEPROP 2 LAST SIG_NAME P5E_CPU0_PE4_TX_C_DP<8>
J 0
(1315 -1065);
DISPLAY 0.638298 (1315 -1065);
WIRE 16 -1 (2400 1875)(1150 1875);
FORCEPROP 2 LAST SIG_NAME P5E_CPU0_PE0_RX_DN<4>
J 0
(1315 1885);
DISPLAY 0.638298 (1315 1885);
WIRE 16 -1 (2400 1825)(1150 1825);
FORCEPROP 2 LAST SIG_NAME P5E_CPU0_PE0_RX_DP<4>
J 0
(1315 1835);
DISPLAY 0.638298 (1315 1835);
WIRE 16 -1 (2400 1725)(1150 1725);
FORCEPROP 2 LAST SIG_NAME P5E_CPU0_PE4_RX_DP<11>
J 0
(1315 1735);
DISPLAY 0.638298 (1315 1735);
WIRE 16 -1 (2400 1675)(1150 1675);
FORCEPROP 2 LAST SIG_NAME P5E_CPU0_PE4_RX_DN<11>
J 0
(1315 1685);
DISPLAY 0.638298 (1315 1685);
WIRE 16 -1 (2400 1575)(1150 1575);
FORCEPROP 2 LAST SIG_NAME P5E_CPU0_PE0_TX_C_DN<4>
J 0
(1315 1585);
DISPLAY 0.638298 (1315 1585);
WIRE 16 -1 (2400 1425)(1150 1425);
FORCEPROP 2 LAST SIG_NAME P5E_CPU0_PE4_TX_C_DP<11>
J 0
(1315 1435);
DISPLAY 0.638298 (1315 1435);
WIRE 16 -1 (2400 1025)(1150 1025);
FORCEPROP 2 LAST SIG_NAME P5E_CPU0_PE0_RX_DN<5>
J 0
(1315 1035);
DISPLAY 0.638298 (1315 1035);
WIRE 16 -1 (2400 575)(1150 575);
FORCEPROP 2 LAST SIG_NAME P5E_CPU0_PE4_TX_C_DN<10>
J 0
(1315 585);
DISPLAY 0.638298 (1315 585);
WIRE 16 -1 (2400 -1025)(1175 -1025);
FORCEPROP 2 LAST SIG_NAME P5E_CPU0_PE4_TX_C_DN<8>
J 0
(1315 -1015);
DISPLAY 0.638298 (1315 -1015);
WIRE 16 -1 (-2100 225)(-3325 225);
FORCEPROP 2 LAST SIG_NAME P5E_CPU0_PE0_RX_DP<2>
J 0
(-3160 235);
DISPLAY 0.638298 (-3160 235);
WIRE 16 -1 (-2100 -175)(-3325 -175);
FORCEPROP 2 LAST SIG_NAME P5E_CPU0_PE4_TX_C_DN<13>
J 0
(-3160 -165);
DISPLAY 0.638298 (-3160 -165);
WIRE 16 -1 (-2100 -225)(-3325 -225);
FORCEPROP 2 LAST SIG_NAME P5E_CPU0_PE4_TX_C_DP<13>
J 0
(-3160 -215);
DISPLAY 0.638298 (-3160 -215);
WIRE 16 -1 (-2100 -875)(-3325 -875);
FORCEPROP 2 LAST SIG_NAME P5E_CPU0_PE0_TX_C_DN<3>
J 0
(-3160 -865);
DISPLAY 0.638298 (-3160 -865);
WIRE 16 -1 (-2100 -725)(-3325 -725);
FORCEPROP 2 LAST SIG_NAME P5E_CPU0_PE4_RX_DN<12>
J 0
(-3160 -715);
DISPLAY 0.638298 (-3160 -715);
WIRE 16 -1 (-2100 -575)(-3325 -575);
FORCEPROP 2 LAST SIG_NAME P5E_CPU0_PE0_RX_DP<3>
J 0
(-3160 -565);
DISPLAY 0.638298 (-3160 -565);
WIRE 16 -1 (-2100 -75)(-3325 -75);
FORCEPROP 2 LAST SIG_NAME P5E_CPU0_PE0_TX_C_DP<2>
J 0
(-3160 -65);
DISPLAY 0.638298 (-3160 -65);
WIRE 16 -1 (-2100 -25)(-3325 -25);
FORCEPROP 2 LAST SIG_NAME P5E_CPU0_PE0_TX_C_DN<2>
J 0
(-3160 -15);
DISPLAY 0.638298 (-3160 -15);
WIRE 16 -1 (-2100 125)(-3325 125);
FORCEPROP 2 LAST SIG_NAME P5E_CPU0_PE4_RX_DP<13>
J 0
(-3160 135);
DISPLAY 0.638298 (-3160 135);
WIRE 16 -1 (-2100 -1075)(-3325 -1075);
FORCEPROP 2 LAST SIG_NAME P5E_CPU0_PE4_TX_C_DP<12>
J 0
(-3160 -1065);
DISPLAY 0.638298 (-3160 -1065);
DOT 1 (2175 -275);
DOT 1 (-2275 1325);
DOT 1 (-2275 -1125);
DOT 1 (-2275 -975);
DOT 1 (-2275 -825);
DOT 1 (-2275 -675);
DOT 1 (-2275 -525);
DOT 1 (-2275 -275);
DOT 1 (-2275 -125);
DOT 1 (-2275 175);
DOT 1 (-2275 25);
DOT 1 (-2275 475);
DOT 1 (-2275 325);
DOT 1 (-2275 625);
DOT 1 (-2275 775);
DOT 1 (-2275 1075);
DOT 1 (-2275 1775);
DOT 1 (-2275 1625);
DOT 1 (-2275 1475);
DOT 1 (2175 -1125);
DOT 1 (2175 -975);
DOT 1 (2175 -825);
DOT 1 (2175 -525);
DOT 1 (2175 -125);
DOT 1 (2175 25);
DOT 1 (2175 175);
DOT 1 (2175 325);
DOT 1 (2175 475);
DOT 1 (2175 775);
DOT 1 (2175 625);
DOT 1 (2175 925);
DOT 1 (2175 1075);
DOT 1 (2175 1325);
DOT 1 (2175 1475);
DOT 1 (2175 1625);
DOT 1 (2175 1775);
DOT 1 (2175 -675);
DOT 1 (-2275 925);
FORCENOTE
DP/DN SWAP
(250 100) 0;
DISPLAY LEFT (250 100);
DISPLAY 1.021277 (250 100);
FORCENOTE
DP/DN SWAP
(-4225 975) 0;
DISPLAY LEFT (-4225 975);
DISPLAY 1.021277 (-4225 975);
FORCENOTE
20210527 MODIFY FOR GT
(-4475 3025) 0;
DISPLAY LEFT (-4475 3025);
DISPLAY 2.510638 (-4475 3025);
PAINT PINK (-4475 3025);
FORCENOTE
DP/DN SWAP
(250 1675) 0;
DISPLAY LEFT (250 1675);
DISPLAY 1.021277 (250 1675);
FORCENOTE
DP/DN SWAP
(225 1375) 0;
DISPLAY LEFT (225 1375);
DISPLAY 1.021277 (225 1375);
FORCENOTE
DP/DN SWAP
(-4225 -625) 0;
DISPLAY LEFT (-4225 -625);
DISPLAY 1.021277 (-4225 -625);
FORCENOTE
DP/DN SWAP
(-4175 100) 0;
DISPLAY LEFT (-4175 100);
DISPLAY 1.021277 (-4175 100);
FORCENOTE
DP/DN SWAP
(-4200 1700) 0;
DISPLAY LEFT (-4200 1700);
DISPLAY 1.021277 (-4200 1700);
FORCENOTE
CPU0_PE4_TX/RX<0-15> LANE REVERSAL
(-4375 2250) 0;
DISPLAY LEFT (-4375 2250);
DISPLAY 1.276596 (-4375 2250);
PAINT WHITE (-4375 2250);
QUIT
